FILE_TYPE = MACRO_DRAWING;
SET COLOR_WIRE YELLOW;
SET COLOR_PROP ORANGE;
SET COLOR_DOT WHITE;
SET COLOR_ARC YELLOW;
SET COLOR_BODY GREEN;
SET COLOR_NOTE PURPLE;
SET PROP_DISPLAY VALUE;
SET PAGE_NUMBER P89;
FORCEADD GND..1
(-2300 2175);
FORCEPROP 3 LASTPIN (-2300 2225) SIG_NAME GND\g
J 0
(-2290 2235);
DISPLAY 0.659574 (-2290 2235);
PAINT MONO (-2290 2235);
DISPLAY INVISIBLE (-2290 2235);
FORCEPROP 2 LAST CDS_LIB mstr_symbols
J 0
(-2300 2175);
DISPLAY 0.723404 (-2300 2175);
DISPLAY INVISIBLE (-2300 2175);
FORCEPROP 1 LAST SIZE 1B
J 0
(-2225 2125);
DISPLAY 0.851064 (-2225 2125);
PAINT GREEN (-2225 2125);
DISPLAY INVISIBLE (-2225 2125);
FORCEPROP 1 LAST VOLTAGE 0.0
J 0
(-2345 2132);
DISPLAY 0.723404 (-2345 2132);
PAINT SKYBLUE (-2345 2132);
DISPLAY INVISIBLE (-2345 2132);
FORCEPROP 1 LAST BODY_TYPE PLUMBING
J 0
(-2345 2132);
DISPLAY 0.340426 (-2345 2132);
PAINT GREEN (-2345 2132);
DISPLAY INVISIBLE (-2345 2132);
FORCEPROP 1 LAST HDL_POWER GND
J 0
(-2300 2325);
DISPLAY 0.851064 (-2300 2325);
PAINT GREEN (-2300 2325);
DISPLAY INVISIBLE (-2300 2325);
FORCEPROP 1 LAST PATH I150
J 0
(-2225 2175);
DISPLAY 0.872340 (-2225 2175);
PAINT GREEN (-2225 2175);
DISPLAY INVISIBLE (-2225 2175);
FORCEADD GND..1
(-500 2000);
FORCEPROP 3 LASTPIN (-500 2050) SIG_NAME GND\g
J 0
(-490 2060);
DISPLAY 0.659574 (-490 2060);
PAINT MONO (-490 2060);
DISPLAY INVISIBLE (-490 2060);
FORCEPROP 1 LAST SIZE 1B
J 0
(-425 1950);
DISPLAY 0.851064 (-425 1950);
PAINT GREEN (-425 1950);
DISPLAY INVISIBLE (-425 1950);
FORCEPROP 2 LAST CDS_LIB mstr_symbols
J 0
(-500 2000);
DISPLAY 0.723404 (-500 2000);
DISPLAY INVISIBLE (-500 2000);
FORCEPROP 1 LAST VOLTAGE 0.0
J 0
(-545 1957);
DISPLAY 0.723404 (-545 1957);
PAINT SKYBLUE (-545 1957);
DISPLAY INVISIBLE (-545 1957);
FORCEPROP 1 LAST BODY_TYPE PLUMBING
J 0
(-545 1957);
DISPLAY 0.340426 (-545 1957);
PAINT GREEN (-545 1957);
DISPLAY INVISIBLE (-545 1957);
FORCEPROP 1 LAST HDL_POWER GND
J 0
(-500 2150);
DISPLAY 0.851064 (-500 2150);
PAINT GREEN (-500 2150);
DISPLAY INVISIBLE (-500 2150);
FORCEPROP 1 LAST PATH I152
J 0
(-425 2000);
DISPLAY 0.872340 (-425 2000);
PAINT GREEN (-425 2000);
DISPLAY INVISIBLE (-425 2000);
FORCEADD OFFPAGE..5
(-8575 2125);
FORCEPROP 2 LAST $XR0 14 
J 0
(-8799 2125);
DISPLAY 0.638298 (-8799 2125);
PAINT MONO (-8799 2125);
FORCEPROP 2 LAST CDS_LIB mstr_standard
J 0
(-8575 2125);
DISPLAY 0.808511 (-8575 2125);
DISPLAY INVISIBLE (-8575 2125);
FORCEPROP 1 LAST OFFPAGE TRUE
J 0
(-8250 2000);
DISPLAY 0.872340 (-8250 2000);
PAINT GREEN (-8250 2000);
DISPLAY INVISIBLE (-8250 2000);
FORCEPROP 1 LAST COMMENT_BODY TRUE
J 0
(-8475 2050);
DISPLAY 0.872340 (-8475 2050);
PAINT GREEN (-8475 2050);
DISPLAY INVISIBLE (-8475 2050);
FORCEPROP 2 LAST PATH I167
J 0
(-8525 2200);
DISPLAY 0.808511 (-8525 2200);
DISPLAY INVISIBLE (-8525 2200);
FORCEADD OFFPAGE..5
(-8575 2175);
FORCEPROP 2 LAST $XR0 14 
J 0
(-8799 2175);
DISPLAY 0.638298 (-8799 2175);
PAINT MONO (-8799 2175);
FORCEPROP 2 LAST CDS_LIB mstr_standard
J 0
(-8575 2175);
DISPLAY 0.808511 (-8575 2175);
DISPLAY INVISIBLE (-8575 2175);
FORCEPROP 1 LAST OFFPAGE TRUE
J 0
(-8250 2050);
DISPLAY 0.872340 (-8250 2050);
PAINT GREEN (-8250 2050);
DISPLAY INVISIBLE (-8250 2050);
FORCEPROP 1 LAST COMMENT_BODY TRUE
J 0
(-8475 2100);
DISPLAY 0.872340 (-8475 2100);
PAINT GREEN (-8475 2100);
DISPLAY INVISIBLE (-8475 2100);
FORCEPROP 2 LAST PATH I168
J 0
(-8525 2250);
DISPLAY 0.808511 (-8525 2250);
DISPLAY INVISIBLE (-8525 2250);
FORCEADD OFFPAGE..6
(-8575 3775);
FORCEPROP 2 LAST $XR0 14 
J 0
(-8854 3775);
DISPLAY 0.638298 (-8854 3775);
PAINT MONO (-8854 3775);
FORCEPROP 2 LAST CDS_LIB mstr_standard
J 0
(-8575 3775);
DISPLAY 0.723404 (-8575 3775);
PAINT MONO (-8575 3775);
DISPLAY INVISIBLE (-8575 3775);
FORCEPROP 1 LAST OFFPAGE TRUE
J 0
(-8250 3650);
DISPLAY 0.872340 (-8250 3650);
PAINT GREEN (-8250 3650);
DISPLAY INVISIBLE (-8250 3650);
FORCEPROP 1 LAST COMMENT_BODY TRUE
J 0
(-8475 3700);
DISPLAY 0.872340 (-8475 3700);
PAINT GREEN (-8475 3700);
DISPLAY INVISIBLE (-8475 3700);
FORCEPROP 2 LAST PATH I174
J 0
(-8525 3850);
DISPLAY 0.808511 (-8525 3850);
DISPLAY INVISIBLE (-8525 3850);
FORCEADD OFFPAGE..1
(-8425 3275);
FORCEPROP 2 LAST $XR0 14 
J 0
(-8646 3275);
DISPLAY 0.638298 (-8646 3275);
PAINT MONO (-8646 3275);
FORCEPROP 2 LAST CDS_LIB mstr_standard
J 0
(-8425 3275);
DISPLAY 0.808511 (-8425 3275);
DISPLAY INVISIBLE (-8425 3275);
FORCEPROP 1 LAST OFFPAGE TRUE
J 0
(-8100 3150);
DISPLAY 0.872340 (-8100 3150);
PAINT GREEN (-8100 3150);
DISPLAY INVISIBLE (-8100 3150);
FORCEPROP 1 LAST COMMENT_BODY TRUE
J 0
(-8300 3175);
DISPLAY 0.872340 (-8300 3175);
PAINT GREEN (-8300 3175);
DISPLAY INVISIBLE (-8300 3175);
FORCEPROP 2 LAST PATH I176
J 0
(-8625 3500);
DISPLAY 0.808511 (-8625 3500);
DISPLAY INVISIBLE (-8625 3500);
FORCEADD VCC_CORE..1
(-8775 3650);
FORCEPROP 3 LASTPIN (-8775 3600) SIG_NAME P3V3_AUX\g
J 0
(-8765 3610);
DISPLAY 0.659574 (-8765 3610);
PAINT MONO (-8765 3610);
DISPLAY INVISIBLE (-8765 3610);
FORCEPROP 1 LAST HDL_POWER P3V3_AUX
J 1
(-8775 3700);
DISPLAY 0.489362 (-8775 3700);
PAINT GREEN (-8775 3700);
FORCEPROP 2 LAST CDS_LIB mstr_symbols
J 0
(-8775 3650);
PAINT MONO (-8775 3650);
DISPLAY INVISIBLE (-8775 3650);
FORCEPROP 0 LAST VOLTAGE 3.3
J 0
(-9050 3800);
DISPLAY 1.021277 (-9050 3800);
PAINT SKYBLUE (-9050 3800);
DISPLAY INVISIBLE (-9050 3800);
FORCEPROP 2 LAST ROOM PVCCINFAON_CPU0_CTRL
J 0
(-8775 3750);
DISPLAY 0.808511 (-8775 3750);
PAINT RED (-8775 3750);
DISPLAY INVISIBLE (-8775 3750);
FORCEPROP 1 LAST PATH I177
J 0
(-8725 3675);
DISPLAY 0.872340 (-8725 3675);
PAINT GREEN (-8725 3675);
DISPLAY INVISIBLE (-8725 3675);
FORCEADD OFFPAGE..1
(-8575 4275);
FORCEPROP 2 LAST $XR0 14 
J 0
(-8826 4275);
DISPLAY 0.638298 (-8826 4275);
PAINT MONO (-8826 4275);
FORCEPROP 2 LAST CDS_LIB mstr_standard
J 0
(-8575 4275);
DISPLAY 0.808511 (-8575 4275);
DISPLAY INVISIBLE (-8575 4275);
FORCEPROP 1 LAST OFFPAGE TRUE
J 0
(-8250 4150);
DISPLAY 0.872340 (-8250 4150);
PAINT GREEN (-8250 4150);
DISPLAY INVISIBLE (-8250 4150);
FORCEPROP 1 LAST COMMENT_BODY TRUE
J 0
(-8450 4175);
DISPLAY 0.872340 (-8450 4175);
PAINT GREEN (-8450 4175);
DISPLAY INVISIBLE (-8450 4175);
FORCEPROP 2 LAST PATH I178
J 0
(-8525 4350);
DISPLAY 0.808511 (-8525 4350);
DISPLAY INVISIBLE (-8525 4350);
FORCEADD OFFPAGE..6
(-8575 4225);
FORCEPROP 2 LAST $XR0 14 
J 0
(-8854 4225);
DISPLAY 0.638298 (-8854 4225);
PAINT MONO (-8854 4225);
FORCEPROP 2 LAST CDS_LIB mstr_standard
J 0
(-8575 4225);
DISPLAY 0.723404 (-8575 4225);
PAINT MONO (-8575 4225);
DISPLAY INVISIBLE (-8575 4225);
FORCEPROP 1 LAST OFFPAGE TRUE
J 0
(-8250 4100);
DISPLAY 0.872340 (-8250 4100);
PAINT GREEN (-8250 4100);
DISPLAY INVISIBLE (-8250 4100);
FORCEPROP 1 LAST COMMENT_BODY TRUE
J 0
(-8475 4150);
DISPLAY 0.872340 (-8475 4150);
PAINT GREEN (-8475 4150);
DISPLAY INVISIBLE (-8475 4150);
FORCEPROP 2 LAST PATH I179
J 0
(-8525 4300);
DISPLAY 0.808511 (-8525 4300);
DISPLAY INVISIBLE (-8525 4300);
FORCEADD OFFPAGE..1
(-8575 4325);
FORCEPROP 2 LAST $XR0 14 
J 0
(-8826 4325);
DISPLAY 0.638298 (-8826 4325);
PAINT MONO (-8826 4325);
FORCEPROP 2 LAST CDS_LIB mstr_standard
J 0
(-8575 4325);
DISPLAY 0.723404 (-8575 4325);
PAINT MONO (-8575 4325);
DISPLAY INVISIBLE (-8575 4325);
FORCEPROP 1 LAST OFFPAGE TRUE
J 0
(-8250 4200);
DISPLAY 0.872340 (-8250 4200);
PAINT GREEN (-8250 4200);
DISPLAY INVISIBLE (-8250 4200);
FORCEPROP 1 LAST COMMENT_BODY TRUE
J 0
(-8450 4225);
DISPLAY 0.872340 (-8450 4225);
PAINT GREEN (-8450 4225);
DISPLAY INVISIBLE (-8450 4225);
FORCEPROP 2 LAST PATH I180
J 0
(-8525 4400);
DISPLAY 0.808511 (-8525 4400);
DISPLAY INVISIBLE (-8525 4400);
FORCEADD OFFPAGE..1
(-8575 4425);
FORCEPROP 2 LAST $XR0 14 
J 0
(-8826 4425);
DISPLAY 0.638298 (-8826 4425);
PAINT MONO (-8826 4425);
FORCEPROP 2 LAST CDS_LIB mstr_standard
J 0
(-8575 4425);
DISPLAY 0.808511 (-8575 4425);
DISPLAY INVISIBLE (-8575 4425);
FORCEPROP 1 LAST OFFPAGE TRUE
J 0
(-8250 4300);
DISPLAY 0.872340 (-8250 4300);
PAINT GREEN (-8250 4300);
DISPLAY INVISIBLE (-8250 4300);
FORCEPROP 1 LAST COMMENT_BODY TRUE
J 0
(-8450 4325);
DISPLAY 0.872340 (-8450 4325);
PAINT GREEN (-8450 4325);
DISPLAY INVISIBLE (-8450 4325);
FORCEPROP 2 LAST PATH I181
J 0
(-8525 4500);
DISPLAY 0.808511 (-8525 4500);
DISPLAY INVISIBLE (-8525 4500);
FORCEADD OFFPAGE..1
(-8575 4475);
FORCEPROP 2 LAST $XR0 14 
J 0
(-8826 4475);
DISPLAY 0.638298 (-8826 4475);
PAINT MONO (-8826 4475);
FORCEPROP 2 LAST CDS_LIB mstr_standard
J 0
(-8575 4475);
DISPLAY 0.723404 (-8575 4475);
PAINT MONO (-8575 4475);
DISPLAY INVISIBLE (-8575 4475);
FORCEPROP 1 LAST OFFPAGE TRUE
J 0
(-8250 4350);
DISPLAY 0.872340 (-8250 4350);
PAINT GREEN (-8250 4350);
DISPLAY INVISIBLE (-8250 4350);
FORCEPROP 1 LAST COMMENT_BODY TRUE
J 0
(-8450 4375);
DISPLAY 0.872340 (-8450 4375);
PAINT GREEN (-8450 4375);
DISPLAY INVISIBLE (-8450 4375);
FORCEPROP 2 LAST PATH I182
J 0
(-8525 4550);
DISPLAY 0.808511 (-8525 4550);
DISPLAY INVISIBLE (-8525 4550);
FORCEADD OFFPAGE..1
(-8575 4575);
FORCEPROP 2 LAST $XR0 14 
J 0
(-8826 4575);
DISPLAY 0.638298 (-8826 4575);
PAINT MONO (-8826 4575);
FORCEPROP 2 LAST CDS_LIB mstr_standard
J 0
(-8575 4575);
DISPLAY 0.808511 (-8575 4575);
DISPLAY INVISIBLE (-8575 4575);
FORCEPROP 1 LAST OFFPAGE TRUE
J 0
(-8250 4450);
DISPLAY 0.872340 (-8250 4450);
PAINT GREEN (-8250 4450);
DISPLAY INVISIBLE (-8250 4450);
FORCEPROP 1 LAST COMMENT_BODY TRUE
J 0
(-8450 4475);
DISPLAY 0.872340 (-8450 4475);
PAINT GREEN (-8450 4475);
DISPLAY INVISIBLE (-8450 4475);
FORCEPROP 2 LAST PATH I183
J 0
(-8525 4650);
DISPLAY 0.808511 (-8525 4650);
DISPLAY INVISIBLE (-8525 4650);
FORCEADD OFFPAGE..1
(-8575 4625);
FORCEPROP 2 LAST $XR0 14 
J 0
(-8826 4625);
DISPLAY 0.638298 (-8826 4625);
PAINT MONO (-8826 4625);
FORCEPROP 2 LAST CDS_LIB mstr_standard
J 0
(-8575 4625);
DISPLAY 0.723404 (-8575 4625);
PAINT MONO (-8575 4625);
DISPLAY INVISIBLE (-8575 4625);
FORCEPROP 1 LAST OFFPAGE TRUE
J 0
(-8250 4500);
DISPLAY 0.872340 (-8250 4500);
PAINT GREEN (-8250 4500);
DISPLAY INVISIBLE (-8250 4500);
FORCEPROP 1 LAST COMMENT_BODY TRUE
J 0
(-8450 4525);
DISPLAY 0.872340 (-8450 4525);
PAINT GREEN (-8450 4525);
DISPLAY INVISIBLE (-8450 4525);
FORCEPROP 2 LAST PATH I184
J 0
(-8525 4700);
DISPLAY 0.808511 (-8525 4700);
DISPLAY INVISIBLE (-8525 4700);
FORCEADD OFFPAGE..1
(-8575 4775);
FORCEPROP 2 LAST $XR0 14 
J 0
(-8826 4775);
DISPLAY 0.638298 (-8826 4775);
PAINT MONO (-8826 4775);
FORCEPROP 2 LAST CDS_LIB mstr_standard
J 0
(-8575 4775);
DISPLAY 0.723404 (-8575 4775);
PAINT MONO (-8575 4775);
DISPLAY INVISIBLE (-8575 4775);
FORCEPROP 1 LAST OFFPAGE TRUE
J 0
(-8250 4650);
DISPLAY 0.872340 (-8250 4650);
PAINT GREEN (-8250 4650);
DISPLAY INVISIBLE (-8250 4650);
FORCEPROP 1 LAST COMMENT_BODY TRUE
J 0
(-8450 4675);
DISPLAY 0.872340 (-8450 4675);
PAINT GREEN (-8450 4675);
DISPLAY INVISIBLE (-8450 4675);
FORCEPROP 2 LAST PATH I185
J 0
(-8525 4850);
DISPLAY 0.808511 (-8525 4850);
DISPLAY INVISIBLE (-8525 4850);
FORCEADD OFFPAGE..1
(-8575 4725);
FORCEPROP 2 LAST $XR0 14 
J 0
(-8826 4725);
DISPLAY 0.638298 (-8826 4725);
PAINT MONO (-8826 4725);
FORCEPROP 2 LAST CDS_LIB mstr_standard
J 0
(-8575 4725);
DISPLAY 0.808511 (-8575 4725);
DISPLAY INVISIBLE (-8575 4725);
FORCEPROP 1 LAST OFFPAGE TRUE
J 0
(-8250 4600);
DISPLAY 0.872340 (-8250 4600);
PAINT GREEN (-8250 4600);
DISPLAY INVISIBLE (-8250 4600);
FORCEPROP 1 LAST COMMENT_BODY TRUE
J 0
(-8450 4625);
DISPLAY 0.872340 (-8450 4625);
PAINT GREEN (-8450 4625);
DISPLAY INVISIBLE (-8450 4625);
FORCEPROP 2 LAST PATH I186
J 0
(-8525 4800);
DISPLAY 0.808511 (-8525 4800);
DISPLAY INVISIBLE (-8525 4800);
FORCEADD TAP..1
R 2
(-7975 3425);
FORCEPROP 3 LASTPIN (-7925 3425) SIG_NAME M_E_CPU0_SB_CB<1>
J 0
(-7915 3435);
DISPLAY 0.659574 (-7915 3435);
PAINT MONO (-7915 3435);
DISPLAY INVISIBLE (-7915 3435);
FORCEPROP 1 LASTPIN (-7925 3425) BN 1
J 2
(-7913 3433);
DISPLAY 0.489362 (-7913 3433);
PAINT GREEN (-7913 3433);
FORCEPROP 2 LAST CDS_LIB mstr_standard
J 0
(-7975 3425);
DISPLAY 0.723404 (-7975 3425);
PAINT MONO (-7975 3425);
DISPLAY INVISIBLE (-7975 3425);
FORCEPROP 1 LAST BODY_TYPE PLUMBING
J 2
(-7975 3475);
DISPLAY 0.872340 (-7975 3475);
PAINT GREEN (-7975 3475);
DISPLAY INVISIBLE (-7975 3475);
FORCEPROP 1 LAST HDL_TAP TRUE
J 2
(-8300 3300);
DISPLAY 0.872340 (-8300 3300);
DISPLAY INVISIBLE (-8300 3300);
FORCEPROP 1 LAST PATH I187
J 2
(-7973 3425);
DISPLAY 0.872340 (-7973 3425);
PAINT GREEN (-7973 3425);
DISPLAY INVISIBLE (-7973 3425);
FORCEADD TAP..1
R 2
(-7975 3475);
FORCEPROP 3 LASTPIN (-7925 3475) SIG_NAME M_E_CPU0_SB_CB<2>
J 0
(-7915 3485);
DISPLAY 0.659574 (-7915 3485);
PAINT MONO (-7915 3485);
DISPLAY INVISIBLE (-7915 3485);
FORCEPROP 1 LASTPIN (-7925 3475) BN 2
J 2
(-7913 3483);
DISPLAY 0.489362 (-7913 3483);
PAINT GREEN (-7913 3483);
FORCEPROP 2 LAST CDS_LIB mstr_standard
J 0
(-7975 3475);
DISPLAY 0.723404 (-7975 3475);
PAINT MONO (-7975 3475);
DISPLAY INVISIBLE (-7975 3475);
FORCEPROP 1 LAST BODY_TYPE PLUMBING
J 2
(-7975 3525);
DISPLAY 0.872340 (-7975 3525);
PAINT GREEN (-7975 3525);
DISPLAY INVISIBLE (-7975 3525);
FORCEPROP 1 LAST HDL_TAP TRUE
J 2
(-8300 3350);
DISPLAY 0.872340 (-8300 3350);
DISPLAY INVISIBLE (-8300 3350);
FORCEPROP 1 LAST PATH I188
J 2
(-7973 3475);
DISPLAY 0.872340 (-7973 3475);
PAINT GREEN (-7973 3475);
DISPLAY INVISIBLE (-7973 3475);
FORCEADD TAP..1
R 2
(-7975 3375);
FORCEPROP 3 LASTPIN (-7925 3375) SIG_NAME M_E_CPU0_SB_CB<0>
J 0
(-7915 3385);
DISPLAY 0.659574 (-7915 3385);
PAINT MONO (-7915 3385);
DISPLAY INVISIBLE (-7915 3385);
FORCEPROP 1 LASTPIN (-7925 3375) BN 0
J 2
(-7913 3383);
DISPLAY 0.489362 (-7913 3383);
PAINT GREEN (-7913 3383);
FORCEPROP 2 LAST CDS_LIB mstr_standard
J 0
(-7975 3375);
DISPLAY 0.723404 (-7975 3375);
PAINT MONO (-7975 3375);
DISPLAY INVISIBLE (-7975 3375);
FORCEPROP 1 LAST BODY_TYPE PLUMBING
J 2
(-7975 3425);
DISPLAY 0.872340 (-7975 3425);
PAINT GREEN (-7975 3425);
DISPLAY INVISIBLE (-7975 3425);
FORCEPROP 1 LAST HDL_TAP TRUE
J 2
(-8300 3250);
DISPLAY 0.872340 (-8300 3250);
DISPLAY INVISIBLE (-8300 3250);
FORCEPROP 1 LAST PATH I189
J 2
(-7973 3375);
DISPLAY 0.872340 (-7973 3375);
PAINT GREEN (-7973 3375);
DISPLAY INVISIBLE (-7973 3375);
FORCEADD TAP..1
R 2
(-7975 3525);
FORCEPROP 3 LASTPIN (-7925 3525) SIG_NAME M_E_CPU0_SB_CB<3>
J 0
(-7915 3535);
DISPLAY 0.659574 (-7915 3535);
PAINT MONO (-7915 3535);
DISPLAY INVISIBLE (-7915 3535);
FORCEPROP 1 LASTPIN (-7925 3525) BN 3
J 2
(-7913 3533);
DISPLAY 0.489362 (-7913 3533);
PAINT GREEN (-7913 3533);
FORCEPROP 2 LAST CDS_LIB mstr_standard
J 0
(-7975 3525);
DISPLAY 0.723404 (-7975 3525);
PAINT MONO (-7975 3525);
DISPLAY INVISIBLE (-7975 3525);
FORCEPROP 1 LAST BODY_TYPE PLUMBING
J 2
(-7975 3575);
DISPLAY 0.872340 (-7975 3575);
PAINT GREEN (-7975 3575);
DISPLAY INVISIBLE (-7975 3575);
FORCEPROP 1 LAST HDL_TAP TRUE
J 2
(-8300 3400);
DISPLAY 0.872340 (-8300 3400);
DISPLAY INVISIBLE (-8300 3400);
FORCEPROP 1 LAST PATH I190
J 2
(-7973 3525);
DISPLAY 0.872340 (-7973 3525);
PAINT GREEN (-7973 3525);
DISPLAY INVISIBLE (-7973 3525);
FORCEADD TAP..1
R 2
(-7975 3575);
FORCEPROP 3 LASTPIN (-7925 3575) SIG_NAME M_E_CPU0_SB_CB<4>
J 0
(-7915 3585);
DISPLAY 0.659574 (-7915 3585);
PAINT MONO (-7915 3585);
DISPLAY INVISIBLE (-7915 3585);
FORCEPROP 1 LASTPIN (-7925 3575) BN 4
J 2
(-7913 3583);
DISPLAY 0.489362 (-7913 3583);
PAINT GREEN (-7913 3583);
FORCEPROP 2 LAST CDS_LIB mstr_standard
J 0
(-7975 3575);
DISPLAY 0.723404 (-7975 3575);
PAINT MONO (-7975 3575);
DISPLAY INVISIBLE (-7975 3575);
FORCEPROP 1 LAST BODY_TYPE PLUMBING
J 2
(-7975 3625);
DISPLAY 0.872340 (-7975 3625);
PAINT GREEN (-7975 3625);
DISPLAY INVISIBLE (-7975 3625);
FORCEPROP 1 LAST HDL_TAP TRUE
J 2
(-8300 3450);
DISPLAY 0.872340 (-8300 3450);
DISPLAY INVISIBLE (-8300 3450);
FORCEPROP 1 LAST PATH I191
J 2
(-7973 3575);
DISPLAY 0.872340 (-7973 3575);
PAINT GREEN (-7973 3575);
DISPLAY INVISIBLE (-7973 3575);
FORCEADD TAP..1
R 2
(-7975 3625);
FORCEPROP 3 LASTPIN (-7925 3625) SIG_NAME M_E_CPU0_SB_CB<5>
J 0
(-7915 3635);
DISPLAY 0.659574 (-7915 3635);
PAINT MONO (-7915 3635);
DISPLAY INVISIBLE (-7915 3635);
FORCEPROP 1 LASTPIN (-7925 3625) BN 5
J 2
(-7913 3633);
DISPLAY 0.489362 (-7913 3633);
PAINT GREEN (-7913 3633);
FORCEPROP 2 LAST CDS_LIB mstr_standard
J 0
(-7975 3625);
DISPLAY 0.723404 (-7975 3625);
PAINT MONO (-7975 3625);
DISPLAY INVISIBLE (-7975 3625);
FORCEPROP 1 LAST BODY_TYPE PLUMBING
J 2
(-7975 3675);
DISPLAY 0.872340 (-7975 3675);
PAINT GREEN (-7975 3675);
DISPLAY INVISIBLE (-7975 3675);
FORCEPROP 1 LAST HDL_TAP TRUE
J 2
(-8300 3500);
DISPLAY 0.872340 (-8300 3500);
DISPLAY INVISIBLE (-8300 3500);
FORCEPROP 1 LAST PATH I192
J 2
(-7973 3625);
DISPLAY 0.872340 (-7973 3625);
PAINT GREEN (-7973 3625);
DISPLAY INVISIBLE (-7973 3625);
FORCEADD TAP..1
R 2
(-7975 3725);
FORCEPROP 3 LASTPIN (-7925 3725) SIG_NAME M_E_CPU0_SB_CB<7>
J 0
(-7915 3735);
DISPLAY 0.659574 (-7915 3735);
PAINT MONO (-7915 3735);
DISPLAY INVISIBLE (-7915 3735);
FORCEPROP 1 LASTPIN (-7925 3725) BN 7
J 2
(-7913 3733);
DISPLAY 0.489362 (-7913 3733);
PAINT GREEN (-7913 3733);
FORCEPROP 2 LAST CDS_LIB mstr_standard
J 0
(-7975 3725);
DISPLAY 0.723404 (-7975 3725);
PAINT MONO (-7975 3725);
DISPLAY INVISIBLE (-7975 3725);
FORCEPROP 1 LAST BODY_TYPE PLUMBING
J 2
(-7975 3775);
DISPLAY 0.872340 (-7975 3775);
PAINT GREEN (-7975 3775);
DISPLAY INVISIBLE (-7975 3775);
FORCEPROP 1 LAST HDL_TAP TRUE
J 2
(-8300 3600);
DISPLAY 0.872340 (-8300 3600);
DISPLAY INVISIBLE (-8300 3600);
FORCEPROP 1 LAST PATH I193
J 2
(-7973 3725);
DISPLAY 0.872340 (-7973 3725);
PAINT GREEN (-7973 3725);
DISPLAY INVISIBLE (-7973 3725);
FORCEADD TAP..1
R 2
(-7975 3675);
FORCEPROP 3 LASTPIN (-7925 3675) SIG_NAME M_E_CPU0_SB_CB<6>
J 0
(-7915 3685);
DISPLAY 0.659574 (-7915 3685);
PAINT MONO (-7915 3685);
DISPLAY INVISIBLE (-7915 3685);
FORCEPROP 1 LASTPIN (-7925 3675) BN 6
J 2
(-7913 3683);
DISPLAY 0.489362 (-7913 3683);
PAINT GREEN (-7913 3683);
FORCEPROP 2 LAST CDS_LIB mstr_standard
J 0
(-7975 3675);
DISPLAY 0.723404 (-7975 3675);
PAINT MONO (-7975 3675);
DISPLAY INVISIBLE (-7975 3675);
FORCEPROP 1 LAST BODY_TYPE PLUMBING
J 2
(-7975 3725);
DISPLAY 0.872340 (-7975 3725);
PAINT GREEN (-7975 3725);
DISPLAY INVISIBLE (-7975 3725);
FORCEPROP 1 LAST HDL_TAP TRUE
J 2
(-8300 3550);
DISPLAY 0.872340 (-8300 3550);
DISPLAY INVISIBLE (-8300 3550);
FORCEPROP 1 LAST PATH I194
J 2
(-7973 3675);
DISPLAY 0.872340 (-7973 3675);
PAINT GREEN (-7973 3675);
DISPLAY INVISIBLE (-7973 3675);
FORCEADD TAP..1
R 2
(-7975 3925);
FORCEPROP 3 LASTPIN (-7925 3925) SIG_NAME M_E_CPU0_SA_CB<2>
J 0
(-7915 3935);
DISPLAY 0.659574 (-7915 3935);
PAINT MONO (-7915 3935);
DISPLAY INVISIBLE (-7915 3935);
FORCEPROP 1 LASTPIN (-7925 3925) BN 2
J 2
(-7913 3933);
DISPLAY 0.489362 (-7913 3933);
PAINT GREEN (-7913 3933);
FORCEPROP 2 LAST CDS_LIB mstr_standard
J 0
(-7975 3925);
DISPLAY 0.723404 (-7975 3925);
PAINT MONO (-7975 3925);
DISPLAY INVISIBLE (-7975 3925);
FORCEPROP 1 LAST BODY_TYPE PLUMBING
J 2
(-7975 3975);
DISPLAY 0.872340 (-7975 3975);
PAINT GREEN (-7975 3975);
DISPLAY INVISIBLE (-7975 3975);
FORCEPROP 1 LAST HDL_TAP TRUE
J 2
(-8300 3800);
DISPLAY 0.872340 (-8300 3800);
DISPLAY INVISIBLE (-8300 3800);
FORCEPROP 1 LAST PATH I195
J 2
(-7973 3925);
DISPLAY 0.872340 (-7973 3925);
PAINT GREEN (-7973 3925);
DISPLAY INVISIBLE (-7973 3925);
FORCEADD TAP..1
R 2
(-7975 3875);
FORCEPROP 3 LASTPIN (-7925 3875) SIG_NAME M_E_CPU0_SA_CB<1>
J 0
(-7915 3885);
DISPLAY 0.659574 (-7915 3885);
PAINT MONO (-7915 3885);
DISPLAY INVISIBLE (-7915 3885);
FORCEPROP 1 LASTPIN (-7925 3875) BN 1
J 2
(-7913 3883);
DISPLAY 0.489362 (-7913 3883);
PAINT GREEN (-7913 3883);
FORCEPROP 2 LAST CDS_LIB mstr_standard
J 0
(-7975 3875);
DISPLAY 0.723404 (-7975 3875);
PAINT MONO (-7975 3875);
DISPLAY INVISIBLE (-7975 3875);
FORCEPROP 1 LAST BODY_TYPE PLUMBING
J 2
(-7975 3925);
DISPLAY 0.872340 (-7975 3925);
PAINT GREEN (-7975 3925);
DISPLAY INVISIBLE (-7975 3925);
FORCEPROP 1 LAST HDL_TAP TRUE
J 2
(-8300 3750);
DISPLAY 0.872340 (-8300 3750);
DISPLAY INVISIBLE (-8300 3750);
FORCEPROP 1 LAST PATH I196
J 2
(-7973 3875);
DISPLAY 0.872340 (-7973 3875);
PAINT GREEN (-7973 3875);
DISPLAY INVISIBLE (-7973 3875);
FORCEADD TAP..1
R 2
(-7975 3825);
FORCEPROP 3 LASTPIN (-7925 3825) SIG_NAME M_E_CPU0_SA_CB<0>
J 0
(-7915 3835);
DISPLAY 0.659574 (-7915 3835);
PAINT MONO (-7915 3835);
DISPLAY INVISIBLE (-7915 3835);
FORCEPROP 1 LASTPIN (-7925 3825) BN 0
J 2
(-7913 3833);
DISPLAY 0.489362 (-7913 3833);
PAINT GREEN (-7913 3833);
FORCEPROP 2 LAST CDS_LIB mstr_standard
J 0
(-7975 3825);
DISPLAY 0.723404 (-7975 3825);
PAINT MONO (-7975 3825);
DISPLAY INVISIBLE (-7975 3825);
FORCEPROP 1 LAST BODY_TYPE PLUMBING
J 2
(-7975 3875);
DISPLAY 0.872340 (-7975 3875);
PAINT GREEN (-7975 3875);
DISPLAY INVISIBLE (-7975 3875);
FORCEPROP 1 LAST HDL_TAP TRUE
J 2
(-8300 3700);
DISPLAY 0.872340 (-8300 3700);
DISPLAY INVISIBLE (-8300 3700);
FORCEPROP 1 LAST PATH I197
J 2
(-7973 3825);
DISPLAY 0.872340 (-7973 3825);
PAINT GREEN (-7973 3825);
DISPLAY INVISIBLE (-7973 3825);
FORCEADD TAP..1
R 2
(-7975 3975);
FORCEPROP 3 LASTPIN (-7925 3975) SIG_NAME M_E_CPU0_SA_CB<3>
J 0
(-7915 3985);
DISPLAY 0.659574 (-7915 3985);
PAINT MONO (-7915 3985);
DISPLAY INVISIBLE (-7915 3985);
FORCEPROP 1 LASTPIN (-7925 3975) BN 3
J 2
(-7913 3983);
DISPLAY 0.489362 (-7913 3983);
PAINT GREEN (-7913 3983);
FORCEPROP 2 LAST CDS_LIB mstr_standard
J 0
(-7975 3975);
DISPLAY 0.723404 (-7975 3975);
PAINT MONO (-7975 3975);
DISPLAY INVISIBLE (-7975 3975);
FORCEPROP 1 LAST BODY_TYPE PLUMBING
J 2
(-7975 4025);
DISPLAY 0.872340 (-7975 4025);
PAINT GREEN (-7975 4025);
DISPLAY INVISIBLE (-7975 4025);
FORCEPROP 1 LAST HDL_TAP TRUE
J 2
(-8300 3850);
DISPLAY 0.872340 (-8300 3850);
DISPLAY INVISIBLE (-8300 3850);
FORCEPROP 1 LAST PATH I198
J 2
(-7973 3975);
DISPLAY 0.872340 (-7973 3975);
PAINT GREEN (-7973 3975);
DISPLAY INVISIBLE (-7973 3975);
FORCEADD TAP..1
R 2
(-7975 4025);
FORCEPROP 3 LASTPIN (-7925 4025) SIG_NAME M_E_CPU0_SA_CB<4>
J 0
(-7915 4035);
DISPLAY 0.659574 (-7915 4035);
PAINT MONO (-7915 4035);
DISPLAY INVISIBLE (-7915 4035);
FORCEPROP 1 LASTPIN (-7925 4025) BN 4
J 2
(-7913 4033);
DISPLAY 0.489362 (-7913 4033);
PAINT GREEN (-7913 4033);
FORCEPROP 2 LAST CDS_LIB mstr_standard
J 0
(-7975 4025);
DISPLAY 0.723404 (-7975 4025);
PAINT MONO (-7975 4025);
DISPLAY INVISIBLE (-7975 4025);
FORCEPROP 1 LAST BODY_TYPE PLUMBING
J 2
(-7975 4075);
DISPLAY 0.872340 (-7975 4075);
PAINT GREEN (-7975 4075);
DISPLAY INVISIBLE (-7975 4075);
FORCEPROP 1 LAST HDL_TAP TRUE
J 2
(-8300 3900);
DISPLAY 0.872340 (-8300 3900);
DISPLAY INVISIBLE (-8300 3900);
FORCEPROP 1 LAST PATH I199
J 2
(-7973 4025);
DISPLAY 0.872340 (-7973 4025);
PAINT GREEN (-7973 4025);
DISPLAY INVISIBLE (-7973 4025);
FORCEADD TAP..1
R 2
(-7975 4075);
FORCEPROP 3 LASTPIN (-7925 4075) SIG_NAME M_E_CPU0_SA_CB<5>
J 0
(-7915 4085);
DISPLAY 0.659574 (-7915 4085);
PAINT MONO (-7915 4085);
DISPLAY INVISIBLE (-7915 4085);
FORCEPROP 1 LASTPIN (-7925 4075) BN 5
J 2
(-7913 4083);
DISPLAY 0.489362 (-7913 4083);
PAINT GREEN (-7913 4083);
FORCEPROP 2 LAST CDS_LIB mstr_standard
J 0
(-7975 4075);
DISPLAY 0.723404 (-7975 4075);
PAINT MONO (-7975 4075);
DISPLAY INVISIBLE (-7975 4075);
FORCEPROP 1 LAST BODY_TYPE PLUMBING
J 2
(-7975 4125);
DISPLAY 0.872340 (-7975 4125);
PAINT GREEN (-7975 4125);
DISPLAY INVISIBLE (-7975 4125);
FORCEPROP 1 LAST HDL_TAP TRUE
J 2
(-8300 3950);
DISPLAY 0.872340 (-8300 3950);
DISPLAY INVISIBLE (-8300 3950);
FORCEPROP 1 LAST PATH I200
J 2
(-7973 4075);
DISPLAY 0.872340 (-7973 4075);
PAINT GREEN (-7973 4075);
DISPLAY INVISIBLE (-7973 4075);
FORCEADD TAP..1
R 2
(-7975 4125);
FORCEPROP 3 LASTPIN (-7925 4125) SIG_NAME M_E_CPU0_SA_CB<6>
J 0
(-7915 4135);
DISPLAY 0.659574 (-7915 4135);
PAINT MONO (-7915 4135);
DISPLAY INVISIBLE (-7915 4135);
FORCEPROP 1 LASTPIN (-7925 4125) BN 6
J 2
(-7913 4133);
DISPLAY 0.489362 (-7913 4133);
PAINT GREEN (-7913 4133);
FORCEPROP 2 LAST CDS_LIB mstr_standard
J 0
(-7975 4125);
DISPLAY 0.723404 (-7975 4125);
PAINT MONO (-7975 4125);
DISPLAY INVISIBLE (-7975 4125);
FORCEPROP 1 LAST BODY_TYPE PLUMBING
J 2
(-7975 4175);
DISPLAY 0.872340 (-7975 4175);
PAINT GREEN (-7975 4175);
DISPLAY INVISIBLE (-7975 4175);
FORCEPROP 1 LAST HDL_TAP TRUE
J 2
(-8300 4000);
DISPLAY 0.872340 (-8300 4000);
DISPLAY INVISIBLE (-8300 4000);
FORCEPROP 1 LAST PATH I201
J 2
(-7973 4125);
DISPLAY 0.872340 (-7973 4125);
PAINT GREEN (-7973 4125);
DISPLAY INVISIBLE (-7973 4125);
FORCEADD TAP..1
R 2
(-7975 4175);
FORCEPROP 3 LASTPIN (-7925 4175) SIG_NAME M_E_CPU0_SA_CB<7>
J 0
(-7915 4185);
DISPLAY 0.659574 (-7915 4185);
PAINT MONO (-7915 4185);
DISPLAY INVISIBLE (-7915 4185);
FORCEPROP 1 LASTPIN (-7925 4175) BN 7
J 2
(-7913 4183);
DISPLAY 0.489362 (-7913 4183);
PAINT GREEN (-7913 4183);
FORCEPROP 2 LAST CDS_LIB mstr_standard
J 0
(-7975 4175);
DISPLAY 0.723404 (-7975 4175);
PAINT MONO (-7975 4175);
DISPLAY INVISIBLE (-7975 4175);
FORCEPROP 1 LAST BODY_TYPE PLUMBING
J 2
(-7975 4225);
DISPLAY 0.872340 (-7975 4225);
PAINT GREEN (-7975 4225);
DISPLAY INVISIBLE (-7975 4225);
FORCEPROP 1 LAST HDL_TAP TRUE
J 2
(-8300 4050);
DISPLAY 0.872340 (-8300 4050);
DISPLAY INVISIBLE (-8300 4050);
FORCEPROP 1 LAST PATH I202
J 2
(-7973 4175);
DISPLAY 0.872340 (-7973 4175);
PAINT GREEN (-7973 4175);
DISPLAY INVISIBLE (-7973 4175);
FORCEADD TAP..1
R 2
(-7975 5025);
FORCEPROP 3 LASTPIN (-7925 5025) SIG_NAME M_E_CPU0_SB_CA<3>
J 0
(-7915 5035);
DISPLAY 0.659574 (-7915 5035);
PAINT MONO (-7915 5035);
DISPLAY INVISIBLE (-7915 5035);
FORCEPROP 1 LASTPIN (-7925 5025) BN 3
J 2
(-7913 5033);
DISPLAY 0.489362 (-7913 5033);
PAINT GREEN (-7913 5033);
FORCEPROP 2 LAST CDS_LIB mstr_standard
J 0
(-7975 5025);
DISPLAY 0.723404 (-7975 5025);
PAINT MONO (-7975 5025);
DISPLAY INVISIBLE (-7975 5025);
FORCEPROP 1 LAST BODY_TYPE PLUMBING
J 2
(-7975 5075);
DISPLAY 0.872340 (-7975 5075);
PAINT GREEN (-7975 5075);
DISPLAY INVISIBLE (-7975 5075);
FORCEPROP 1 LAST HDL_TAP TRUE
J 2
(-8300 4900);
DISPLAY 0.872340 (-8300 4900);
DISPLAY INVISIBLE (-8300 4900);
FORCEPROP 1 LAST PATH I203
J 2
(-7973 5025);
DISPLAY 0.872340 (-7973 5025);
PAINT GREEN (-7973 5025);
DISPLAY INVISIBLE (-7973 5025);
FORCEADD TAP..1
R 2
(-7975 4925);
FORCEPROP 3 LASTPIN (-7925 4925) SIG_NAME M_E_CPU0_SB_CA<1>
J 0
(-7915 4935);
DISPLAY 0.659574 (-7915 4935);
PAINT MONO (-7915 4935);
DISPLAY INVISIBLE (-7915 4935);
FORCEPROP 1 LASTPIN (-7925 4925) BN 1
J 2
(-7913 4933);
DISPLAY 0.489362 (-7913 4933);
PAINT GREEN (-7913 4933);
FORCEPROP 2 LAST CDS_LIB mstr_standard
J 0
(-7975 4925);
DISPLAY 0.723404 (-7975 4925);
PAINT MONO (-7975 4925);
DISPLAY INVISIBLE (-7975 4925);
FORCEPROP 1 LAST BODY_TYPE PLUMBING
J 2
(-7975 4975);
DISPLAY 0.872340 (-7975 4975);
PAINT GREEN (-7975 4975);
DISPLAY INVISIBLE (-7975 4975);
FORCEPROP 1 LAST HDL_TAP TRUE
J 2
(-8300 4800);
DISPLAY 0.872340 (-8300 4800);
DISPLAY INVISIBLE (-8300 4800);
FORCEPROP 1 LAST PATH I204
J 2
(-7973 4925);
DISPLAY 0.872340 (-7973 4925);
PAINT GREEN (-7973 4925);
DISPLAY INVISIBLE (-7973 4925);
FORCEADD TAP..1
R 2
(-7975 4875);
FORCEPROP 3 LASTPIN (-7925 4875) SIG_NAME M_E_CPU0_SB_CA<0>
J 0
(-7915 4885);
DISPLAY 0.659574 (-7915 4885);
PAINT MONO (-7915 4885);
DISPLAY INVISIBLE (-7915 4885);
FORCEPROP 1 LASTPIN (-7925 4875) BN 0
J 2
(-7913 4883);
DISPLAY 0.489362 (-7913 4883);
PAINT GREEN (-7913 4883);
FORCEPROP 2 LAST CDS_LIB mstr_standard
J 0
(-7975 4875);
DISPLAY 0.723404 (-7975 4875);
PAINT MONO (-7975 4875);
DISPLAY INVISIBLE (-7975 4875);
FORCEPROP 1 LAST BODY_TYPE PLUMBING
J 2
(-7975 4925);
DISPLAY 0.872340 (-7975 4925);
PAINT GREEN (-7975 4925);
DISPLAY INVISIBLE (-7975 4925);
FORCEPROP 1 LAST HDL_TAP TRUE
J 2
(-8300 4750);
DISPLAY 0.872340 (-8300 4750);
DISPLAY INVISIBLE (-8300 4750);
FORCEPROP 1 LAST PATH I205
J 2
(-7973 4875);
DISPLAY 0.872340 (-7973 4875);
PAINT GREEN (-7973 4875);
DISPLAY INVISIBLE (-7973 4875);
FORCEADD TAP..1
R 2
(-7975 4975);
FORCEPROP 3 LASTPIN (-7925 4975) SIG_NAME M_E_CPU0_SB_CA<2>
J 0
(-7915 4985);
DISPLAY 0.659574 (-7915 4985);
PAINT MONO (-7915 4985);
DISPLAY INVISIBLE (-7915 4985);
FORCEPROP 1 LASTPIN (-7925 4975) BN 2
J 2
(-7913 4983);
DISPLAY 0.489362 (-7913 4983);
PAINT GREEN (-7913 4983);
FORCEPROP 2 LAST CDS_LIB mstr_standard
J 0
(-7975 4975);
DISPLAY 0.723404 (-7975 4975);
PAINT MONO (-7975 4975);
DISPLAY INVISIBLE (-7975 4975);
FORCEPROP 1 LAST BODY_TYPE PLUMBING
J 2
(-7975 5025);
DISPLAY 0.872340 (-7975 5025);
PAINT GREEN (-7975 5025);
DISPLAY INVISIBLE (-7975 5025);
FORCEPROP 1 LAST HDL_TAP TRUE
J 2
(-8300 4850);
DISPLAY 0.872340 (-8300 4850);
DISPLAY INVISIBLE (-8300 4850);
FORCEPROP 1 LAST PATH I206
J 2
(-7973 4975);
DISPLAY 0.872340 (-7973 4975);
PAINT GREEN (-7973 4975);
DISPLAY INVISIBLE (-7973 4975);
FORCEADD TAP..1
(-6275 2425);
FORCEPROP 3 LASTPIN (-6325 2425) SIG_NAME M_E_CPU0_SB_DQ<1>
J 0
(-6315 2435);
DISPLAY 0.659574 (-6315 2435);
PAINT MONO (-6315 2435);
DISPLAY INVISIBLE (-6315 2435);
FORCEPROP 1 LASTPIN (-6325 2425) BN 1
J 0
(-6337 2433);
DISPLAY 0.489362 (-6337 2433);
PAINT GREEN (-6337 2433);
FORCEPROP 2 LAST CDS_LIB mstr_standard
J 0
(-6275 2425);
DISPLAY 0.723404 (-6275 2425);
PAINT MONO (-6275 2425);
DISPLAY INVISIBLE (-6275 2425);
FORCEPROP 1 LAST BODY_TYPE PLUMBING
J 0
(-6275 2475);
DISPLAY 0.872340 (-6275 2475);
PAINT GREEN (-6275 2475);
DISPLAY INVISIBLE (-6275 2475);
FORCEPROP 1 LAST HDL_TAP TRUE
J 0
(-5950 2300);
DISPLAY 0.872340 (-5950 2300);
DISPLAY INVISIBLE (-5950 2300);
FORCEPROP 1 LAST PATH I207
J 0
(-6277 2425);
DISPLAY 0.872340 (-6277 2425);
PAINT GREEN (-6277 2425);
DISPLAY INVISIBLE (-6277 2425);
FORCEADD TAP..1
(-6275 2375);
FORCEPROP 3 LASTPIN (-6325 2375) SIG_NAME M_E_CPU0_SB_DQ<0>
J 0
(-6315 2385);
DISPLAY 0.659574 (-6315 2385);
PAINT MONO (-6315 2385);
DISPLAY INVISIBLE (-6315 2385);
FORCEPROP 1 LASTPIN (-6325 2375) BN 0
J 0
(-6337 2383);
DISPLAY 0.489362 (-6337 2383);
PAINT GREEN (-6337 2383);
FORCEPROP 2 LAST CDS_LIB mstr_standard
J 0
(-6275 2375);
DISPLAY 0.723404 (-6275 2375);
PAINT MONO (-6275 2375);
DISPLAY INVISIBLE (-6275 2375);
FORCEPROP 1 LAST BODY_TYPE PLUMBING
J 0
(-6275 2425);
DISPLAY 0.872340 (-6275 2425);
PAINT GREEN (-6275 2425);
DISPLAY INVISIBLE (-6275 2425);
FORCEPROP 1 LAST HDL_TAP TRUE
J 0
(-5950 2250);
DISPLAY 0.872340 (-5950 2250);
DISPLAY INVISIBLE (-5950 2250);
FORCEPROP 1 LAST PATH I208
J 0
(-6277 2375);
DISPLAY 0.872340 (-6277 2375);
PAINT GREEN (-6277 2375);
DISPLAY INVISIBLE (-6277 2375);
FORCEADD TAP..1
(-6275 2475);
FORCEPROP 3 LASTPIN (-6325 2475) SIG_NAME M_E_CPU0_SB_DQ<2>
J 0
(-6315 2485);
DISPLAY 0.659574 (-6315 2485);
PAINT MONO (-6315 2485);
DISPLAY INVISIBLE (-6315 2485);
FORCEPROP 1 LASTPIN (-6325 2475) BN 2
J 0
(-6337 2483);
DISPLAY 0.489362 (-6337 2483);
PAINT GREEN (-6337 2483);
FORCEPROP 2 LAST CDS_LIB mstr_standard
J 0
(-6275 2475);
DISPLAY 0.723404 (-6275 2475);
PAINT MONO (-6275 2475);
DISPLAY INVISIBLE (-6275 2475);
FORCEPROP 1 LAST BODY_TYPE PLUMBING
J 0
(-6275 2525);
DISPLAY 0.872340 (-6275 2525);
PAINT GREEN (-6275 2525);
DISPLAY INVISIBLE (-6275 2525);
FORCEPROP 1 LAST HDL_TAP TRUE
J 0
(-5950 2350);
DISPLAY 0.872340 (-5950 2350);
DISPLAY INVISIBLE (-5950 2350);
FORCEPROP 1 LAST PATH I209
J 0
(-6277 2475);
DISPLAY 0.872340 (-6277 2475);
PAINT GREEN (-6277 2475);
DISPLAY INVISIBLE (-6277 2475);
FORCEADD TAP..1
(-6275 2525);
FORCEPROP 3 LASTPIN (-6325 2525) SIG_NAME M_E_CPU0_SB_DQ<3>
J 0
(-6315 2535);
DISPLAY 0.659574 (-6315 2535);
PAINT MONO (-6315 2535);
DISPLAY INVISIBLE (-6315 2535);
FORCEPROP 1 LASTPIN (-6325 2525) BN 3
J 0
(-6337 2533);
DISPLAY 0.489362 (-6337 2533);
PAINT GREEN (-6337 2533);
FORCEPROP 2 LAST CDS_LIB mstr_standard
J 0
(-6275 2525);
DISPLAY 0.723404 (-6275 2525);
PAINT MONO (-6275 2525);
DISPLAY INVISIBLE (-6275 2525);
FORCEPROP 1 LAST BODY_TYPE PLUMBING
J 0
(-6275 2575);
DISPLAY 0.872340 (-6275 2575);
PAINT GREEN (-6275 2575);
DISPLAY INVISIBLE (-6275 2575);
FORCEPROP 1 LAST HDL_TAP TRUE
J 0
(-5950 2400);
DISPLAY 0.872340 (-5950 2400);
DISPLAY INVISIBLE (-5950 2400);
FORCEPROP 1 LAST PATH I210
J 0
(-6277 2525);
DISPLAY 0.872340 (-6277 2525);
PAINT GREEN (-6277 2525);
DISPLAY INVISIBLE (-6277 2525);
FORCEADD TAP..1
(-6275 2575);
FORCEPROP 3 LASTPIN (-6325 2575) SIG_NAME M_E_CPU0_SB_DQ<4>
J 0
(-6315 2585);
DISPLAY 0.659574 (-6315 2585);
PAINT MONO (-6315 2585);
DISPLAY INVISIBLE (-6315 2585);
FORCEPROP 1 LASTPIN (-6325 2575) BN 4
J 0
(-6337 2583);
DISPLAY 0.489362 (-6337 2583);
PAINT GREEN (-6337 2583);
FORCEPROP 2 LAST CDS_LIB mstr_standard
J 0
(-6275 2575);
DISPLAY 0.723404 (-6275 2575);
PAINT MONO (-6275 2575);
DISPLAY INVISIBLE (-6275 2575);
FORCEPROP 1 LAST BODY_TYPE PLUMBING
J 0
(-6275 2625);
DISPLAY 0.872340 (-6275 2625);
PAINT GREEN (-6275 2625);
DISPLAY INVISIBLE (-6275 2625);
FORCEPROP 1 LAST HDL_TAP TRUE
J 0
(-5950 2450);
DISPLAY 0.872340 (-5950 2450);
DISPLAY INVISIBLE (-5950 2450);
FORCEPROP 1 LAST PATH I211
J 0
(-6277 2575);
DISPLAY 0.872340 (-6277 2575);
PAINT GREEN (-6277 2575);
DISPLAY INVISIBLE (-6277 2575);
FORCEADD TAP..1
(-6275 2625);
FORCEPROP 3 LASTPIN (-6325 2625) SIG_NAME M_E_CPU0_SB_DQ<5>
J 0
(-6315 2635);
DISPLAY 0.659574 (-6315 2635);
PAINT MONO (-6315 2635);
DISPLAY INVISIBLE (-6315 2635);
FORCEPROP 1 LASTPIN (-6325 2625) BN 5
J 0
(-6337 2633);
DISPLAY 0.489362 (-6337 2633);
PAINT GREEN (-6337 2633);
FORCEPROP 2 LAST CDS_LIB mstr_standard
J 0
(-6275 2625);
DISPLAY 0.723404 (-6275 2625);
PAINT MONO (-6275 2625);
DISPLAY INVISIBLE (-6275 2625);
FORCEPROP 1 LAST BODY_TYPE PLUMBING
J 0
(-6275 2675);
DISPLAY 0.872340 (-6275 2675);
PAINT GREEN (-6275 2675);
DISPLAY INVISIBLE (-6275 2675);
FORCEPROP 1 LAST HDL_TAP TRUE
J 0
(-5950 2500);
DISPLAY 0.872340 (-5950 2500);
DISPLAY INVISIBLE (-5950 2500);
FORCEPROP 1 LAST PATH I212
J 0
(-6277 2625);
DISPLAY 0.872340 (-6277 2625);
PAINT GREEN (-6277 2625);
DISPLAY INVISIBLE (-6277 2625);
FORCEADD TAP..1
(-6275 2725);
FORCEPROP 3 LASTPIN (-6325 2725) SIG_NAME M_E_CPU0_SB_DQ<7>
J 0
(-6315 2735);
DISPLAY 0.659574 (-6315 2735);
PAINT MONO (-6315 2735);
DISPLAY INVISIBLE (-6315 2735);
FORCEPROP 1 LASTPIN (-6325 2725) BN 7
J 0
(-6337 2733);
DISPLAY 0.489362 (-6337 2733);
PAINT GREEN (-6337 2733);
FORCEPROP 2 LAST CDS_LIB mstr_standard
J 0
(-6275 2725);
DISPLAY 0.723404 (-6275 2725);
PAINT MONO (-6275 2725);
DISPLAY INVISIBLE (-6275 2725);
FORCEPROP 1 LAST BODY_TYPE PLUMBING
J 0
(-6275 2775);
DISPLAY 0.872340 (-6275 2775);
PAINT GREEN (-6275 2775);
DISPLAY INVISIBLE (-6275 2775);
FORCEPROP 1 LAST HDL_TAP TRUE
J 0
(-5950 2600);
DISPLAY 0.872340 (-5950 2600);
DISPLAY INVISIBLE (-5950 2600);
FORCEPROP 1 LAST PATH I213
J 0
(-6277 2725);
DISPLAY 0.872340 (-6277 2725);
PAINT GREEN (-6277 2725);
DISPLAY INVISIBLE (-6277 2725);
FORCEADD TAP..1
(-6275 2675);
FORCEPROP 3 LASTPIN (-6325 2675) SIG_NAME M_E_CPU0_SB_DQ<6>
J 0
(-6315 2685);
DISPLAY 0.659574 (-6315 2685);
PAINT MONO (-6315 2685);
DISPLAY INVISIBLE (-6315 2685);
FORCEPROP 1 LASTPIN (-6325 2675) BN 6
J 0
(-6337 2683);
DISPLAY 0.489362 (-6337 2683);
PAINT GREEN (-6337 2683);
FORCEPROP 2 LAST CDS_LIB mstr_standard
J 0
(-6275 2675);
DISPLAY 0.723404 (-6275 2675);
PAINT MONO (-6275 2675);
DISPLAY INVISIBLE (-6275 2675);
FORCEPROP 1 LAST BODY_TYPE PLUMBING
J 0
(-6275 2725);
DISPLAY 0.872340 (-6275 2725);
PAINT GREEN (-6275 2725);
DISPLAY INVISIBLE (-6275 2725);
FORCEPROP 1 LAST HDL_TAP TRUE
J 0
(-5950 2550);
DISPLAY 0.872340 (-5950 2550);
DISPLAY INVISIBLE (-5950 2550);
FORCEPROP 1 LAST PATH I214
J 0
(-6277 2675);
DISPLAY 0.872340 (-6277 2675);
PAINT GREEN (-6277 2675);
DISPLAY INVISIBLE (-6277 2675);
FORCEADD TAP..1
(-6275 2775);
FORCEPROP 3 LASTPIN (-6325 2775) SIG_NAME M_E_CPU0_SB_DQ<8>
J 0
(-6315 2785);
DISPLAY 0.659574 (-6315 2785);
PAINT MONO (-6315 2785);
DISPLAY INVISIBLE (-6315 2785);
FORCEPROP 1 LASTPIN (-6325 2775) BN 8
J 0
(-6337 2783);
DISPLAY 0.489362 (-6337 2783);
PAINT GREEN (-6337 2783);
FORCEPROP 2 LAST CDS_LIB mstr_standard
J 0
(-6275 2775);
DISPLAY 0.723404 (-6275 2775);
PAINT MONO (-6275 2775);
DISPLAY INVISIBLE (-6275 2775);
FORCEPROP 1 LAST BODY_TYPE PLUMBING
J 0
(-6275 2825);
DISPLAY 0.872340 (-6275 2825);
PAINT GREEN (-6275 2825);
DISPLAY INVISIBLE (-6275 2825);
FORCEPROP 1 LAST HDL_TAP TRUE
J 0
(-5950 2650);
DISPLAY 0.872340 (-5950 2650);
DISPLAY INVISIBLE (-5950 2650);
FORCEPROP 1 LAST PATH I215
J 0
(-6277 2775);
DISPLAY 0.872340 (-6277 2775);
PAINT GREEN (-6277 2775);
DISPLAY INVISIBLE (-6277 2775);
FORCEADD TAP..1
(-6275 2825);
FORCEPROP 3 LASTPIN (-6325 2825) SIG_NAME M_E_CPU0_SB_DQ<9>
J 0
(-6315 2835);
DISPLAY 0.659574 (-6315 2835);
PAINT MONO (-6315 2835);
DISPLAY INVISIBLE (-6315 2835);
FORCEPROP 1 LASTPIN (-6325 2825) BN 9
J 0
(-6337 2833);
DISPLAY 0.489362 (-6337 2833);
PAINT GREEN (-6337 2833);
FORCEPROP 2 LAST CDS_LIB mstr_standard
J 0
(-6275 2825);
DISPLAY 0.723404 (-6275 2825);
PAINT MONO (-6275 2825);
DISPLAY INVISIBLE (-6275 2825);
FORCEPROP 1 LAST BODY_TYPE PLUMBING
J 0
(-6275 2875);
DISPLAY 0.872340 (-6275 2875);
PAINT GREEN (-6275 2875);
DISPLAY INVISIBLE (-6275 2875);
FORCEPROP 1 LAST HDL_TAP TRUE
J 0
(-5950 2700);
DISPLAY 0.872340 (-5950 2700);
DISPLAY INVISIBLE (-5950 2700);
FORCEPROP 1 LAST PATH I216
J 0
(-6277 2825);
DISPLAY 0.872340 (-6277 2825);
PAINT GREEN (-6277 2825);
DISPLAY INVISIBLE (-6277 2825);
FORCEADD TAP..1
(-6275 2875);
FORCEPROP 3 LASTPIN (-6325 2875) SIG_NAME M_E_CPU0_SB_DQ<10>
J 0
(-6315 2885);
DISPLAY 0.659574 (-6315 2885);
PAINT MONO (-6315 2885);
DISPLAY INVISIBLE (-6315 2885);
FORCEPROP 1 LASTPIN (-6325 2875) BN 10
J 0
(-6337 2883);
DISPLAY 0.489362 (-6337 2883);
PAINT GREEN (-6337 2883);
FORCEPROP 2 LAST CDS_LIB mstr_standard
J 0
(-6275 2875);
DISPLAY 0.723404 (-6275 2875);
PAINT MONO (-6275 2875);
DISPLAY INVISIBLE (-6275 2875);
FORCEPROP 1 LAST BODY_TYPE PLUMBING
J 0
(-6275 2925);
DISPLAY 0.872340 (-6275 2925);
PAINT GREEN (-6275 2925);
DISPLAY INVISIBLE (-6275 2925);
FORCEPROP 1 LAST HDL_TAP TRUE
J 0
(-5950 2750);
DISPLAY 0.872340 (-5950 2750);
DISPLAY INVISIBLE (-5950 2750);
FORCEPROP 1 LAST PATH I217
J 0
(-6277 2875);
DISPLAY 0.872340 (-6277 2875);
PAINT GREEN (-6277 2875);
DISPLAY INVISIBLE (-6277 2875);
FORCEADD TAP..1
(-6275 2925);
FORCEPROP 3 LASTPIN (-6325 2925) SIG_NAME M_E_CPU0_SB_DQ<11>
J 0
(-6315 2935);
DISPLAY 0.659574 (-6315 2935);
PAINT MONO (-6315 2935);
DISPLAY INVISIBLE (-6315 2935);
FORCEPROP 1 LASTPIN (-6325 2925) BN 11
J 0
(-6337 2933);
DISPLAY 0.489362 (-6337 2933);
PAINT GREEN (-6337 2933);
FORCEPROP 2 LAST CDS_LIB mstr_standard
J 0
(-6275 2925);
DISPLAY 0.723404 (-6275 2925);
PAINT MONO (-6275 2925);
DISPLAY INVISIBLE (-6275 2925);
FORCEPROP 1 LAST BODY_TYPE PLUMBING
J 0
(-6275 2975);
DISPLAY 0.872340 (-6275 2975);
PAINT GREEN (-6275 2975);
DISPLAY INVISIBLE (-6275 2975);
FORCEPROP 1 LAST HDL_TAP TRUE
J 0
(-5950 2800);
DISPLAY 0.872340 (-5950 2800);
DISPLAY INVISIBLE (-5950 2800);
FORCEPROP 1 LAST PATH I218
J 0
(-6277 2925);
DISPLAY 0.872340 (-6277 2925);
PAINT GREEN (-6277 2925);
DISPLAY INVISIBLE (-6277 2925);
FORCEADD TAP..1
(-6275 2975);
FORCEPROP 3 LASTPIN (-6325 2975) SIG_NAME M_E_CPU0_SB_DQ<12>
J 0
(-6315 2985);
DISPLAY 0.659574 (-6315 2985);
PAINT MONO (-6315 2985);
DISPLAY INVISIBLE (-6315 2985);
FORCEPROP 1 LASTPIN (-6325 2975) BN 12
J 0
(-6337 2983);
DISPLAY 0.489362 (-6337 2983);
PAINT GREEN (-6337 2983);
FORCEPROP 2 LAST CDS_LIB mstr_standard
J 0
(-6275 2975);
DISPLAY 0.723404 (-6275 2975);
PAINT MONO (-6275 2975);
DISPLAY INVISIBLE (-6275 2975);
FORCEPROP 1 LAST BODY_TYPE PLUMBING
J 0
(-6275 3025);
DISPLAY 0.872340 (-6275 3025);
PAINT GREEN (-6275 3025);
DISPLAY INVISIBLE (-6275 3025);
FORCEPROP 1 LAST HDL_TAP TRUE
J 0
(-5950 2850);
DISPLAY 0.872340 (-5950 2850);
DISPLAY INVISIBLE (-5950 2850);
FORCEPROP 1 LAST PATH I219
J 0
(-6277 2975);
DISPLAY 0.872340 (-6277 2975);
PAINT GREEN (-6277 2975);
DISPLAY INVISIBLE (-6277 2975);
FORCEADD TAP..1
(-6275 3025);
FORCEPROP 3 LASTPIN (-6325 3025) SIG_NAME M_E_CPU0_SB_DQ<13>
J 0
(-6315 3035);
DISPLAY 0.659574 (-6315 3035);
PAINT MONO (-6315 3035);
DISPLAY INVISIBLE (-6315 3035);
FORCEPROP 1 LASTPIN (-6325 3025) BN 13
J 0
(-6337 3033);
DISPLAY 0.489362 (-6337 3033);
PAINT GREEN (-6337 3033);
FORCEPROP 2 LAST CDS_LIB mstr_standard
J 0
(-6275 3025);
DISPLAY 0.723404 (-6275 3025);
PAINT MONO (-6275 3025);
DISPLAY INVISIBLE (-6275 3025);
FORCEPROP 1 LAST BODY_TYPE PLUMBING
J 0
(-6275 3075);
DISPLAY 0.872340 (-6275 3075);
PAINT GREEN (-6275 3075);
DISPLAY INVISIBLE (-6275 3075);
FORCEPROP 1 LAST HDL_TAP TRUE
J 0
(-5950 2900);
DISPLAY 0.872340 (-5950 2900);
DISPLAY INVISIBLE (-5950 2900);
FORCEPROP 1 LAST PATH I220
J 0
(-6277 3025);
DISPLAY 0.872340 (-6277 3025);
PAINT GREEN (-6277 3025);
DISPLAY INVISIBLE (-6277 3025);
FORCEADD TAP..1
(-6275 3125);
FORCEPROP 3 LASTPIN (-6325 3125) SIG_NAME M_E_CPU0_SB_DQ<15>
J 0
(-6315 3135);
DISPLAY 0.659574 (-6315 3135);
PAINT MONO (-6315 3135);
DISPLAY INVISIBLE (-6315 3135);
FORCEPROP 1 LASTPIN (-6325 3125) BN 15
J 0
(-6337 3133);
DISPLAY 0.489362 (-6337 3133);
PAINT GREEN (-6337 3133);
FORCEPROP 2 LAST CDS_LIB mstr_standard
J 0
(-6275 3125);
DISPLAY 0.723404 (-6275 3125);
PAINT MONO (-6275 3125);
DISPLAY INVISIBLE (-6275 3125);
FORCEPROP 1 LAST BODY_TYPE PLUMBING
J 0
(-6275 3175);
DISPLAY 0.872340 (-6275 3175);
PAINT GREEN (-6275 3175);
DISPLAY INVISIBLE (-6275 3175);
FORCEPROP 1 LAST HDL_TAP TRUE
J 0
(-5950 3000);
DISPLAY 0.872340 (-5950 3000);
DISPLAY INVISIBLE (-5950 3000);
FORCEPROP 1 LAST PATH I221
J 0
(-6277 3125);
DISPLAY 0.872340 (-6277 3125);
PAINT GREEN (-6277 3125);
DISPLAY INVISIBLE (-6277 3125);
FORCEADD TAP..1
(-6275 3075);
FORCEPROP 3 LASTPIN (-6325 3075) SIG_NAME M_E_CPU0_SB_DQ<14>
J 0
(-6315 3085);
DISPLAY 0.659574 (-6315 3085);
PAINT MONO (-6315 3085);
DISPLAY INVISIBLE (-6315 3085);
FORCEPROP 1 LASTPIN (-6325 3075) BN 14
J 0
(-6337 3083);
DISPLAY 0.489362 (-6337 3083);
PAINT GREEN (-6337 3083);
FORCEPROP 2 LAST CDS_LIB mstr_standard
J 0
(-6275 3075);
DISPLAY 0.723404 (-6275 3075);
PAINT MONO (-6275 3075);
DISPLAY INVISIBLE (-6275 3075);
FORCEPROP 1 LAST BODY_TYPE PLUMBING
J 0
(-6275 3125);
DISPLAY 0.872340 (-6275 3125);
PAINT GREEN (-6275 3125);
DISPLAY INVISIBLE (-6275 3125);
FORCEPROP 1 LAST HDL_TAP TRUE
J 0
(-5950 2950);
DISPLAY 0.872340 (-5950 2950);
DISPLAY INVISIBLE (-5950 2950);
FORCEPROP 1 LAST PATH I222
J 0
(-6277 3075);
DISPLAY 0.872340 (-6277 3075);
PAINT GREEN (-6277 3075);
DISPLAY INVISIBLE (-6277 3075);
FORCEADD TAP..1
(-6275 3275);
FORCEPROP 3 LASTPIN (-6325 3275) SIG_NAME M_E_CPU0_SB_DQ<18>
J 0
(-6315 3285);
DISPLAY 0.659574 (-6315 3285);
PAINT MONO (-6315 3285);
DISPLAY INVISIBLE (-6315 3285);
FORCEPROP 1 LASTPIN (-6325 3275) BN 18
J 0
(-6337 3283);
DISPLAY 0.489362 (-6337 3283);
PAINT GREEN (-6337 3283);
FORCEPROP 2 LAST CDS_LIB mstr_standard
J 0
(-6275 3275);
DISPLAY 0.723404 (-6275 3275);
PAINT MONO (-6275 3275);
DISPLAY INVISIBLE (-6275 3275);
FORCEPROP 1 LAST BODY_TYPE PLUMBING
J 0
(-6275 3325);
DISPLAY 0.872340 (-6275 3325);
PAINT GREEN (-6275 3325);
DISPLAY INVISIBLE (-6275 3325);
FORCEPROP 1 LAST HDL_TAP TRUE
J 0
(-5950 3150);
DISPLAY 0.872340 (-5950 3150);
DISPLAY INVISIBLE (-5950 3150);
FORCEPROP 1 LAST PATH I223
J 0
(-6277 3275);
DISPLAY 0.872340 (-6277 3275);
PAINT GREEN (-6277 3275);
DISPLAY INVISIBLE (-6277 3275);
FORCEADD TAP..1
(-6275 3225);
FORCEPROP 3 LASTPIN (-6325 3225) SIG_NAME M_E_CPU0_SB_DQ<17>
J 0
(-6315 3235);
DISPLAY 0.659574 (-6315 3235);
PAINT MONO (-6315 3235);
DISPLAY INVISIBLE (-6315 3235);
FORCEPROP 1 LASTPIN (-6325 3225) BN 17
J 0
(-6337 3233);
DISPLAY 0.489362 (-6337 3233);
PAINT GREEN (-6337 3233);
FORCEPROP 2 LAST CDS_LIB mstr_standard
J 0
(-6275 3225);
DISPLAY 0.723404 (-6275 3225);
PAINT MONO (-6275 3225);
DISPLAY INVISIBLE (-6275 3225);
FORCEPROP 1 LAST BODY_TYPE PLUMBING
J 0
(-6275 3275);
DISPLAY 0.872340 (-6275 3275);
PAINT GREEN (-6275 3275);
DISPLAY INVISIBLE (-6275 3275);
FORCEPROP 1 LAST HDL_TAP TRUE
J 0
(-5950 3100);
DISPLAY 0.872340 (-5950 3100);
DISPLAY INVISIBLE (-5950 3100);
FORCEPROP 1 LAST PATH I224
J 0
(-6277 3225);
DISPLAY 0.872340 (-6277 3225);
PAINT GREEN (-6277 3225);
DISPLAY INVISIBLE (-6277 3225);
FORCEADD TAP..1
(-6275 3175);
FORCEPROP 3 LASTPIN (-6325 3175) SIG_NAME M_E_CPU0_SB_DQ<16>
J 0
(-6315 3185);
DISPLAY 0.659574 (-6315 3185);
PAINT MONO (-6315 3185);
DISPLAY INVISIBLE (-6315 3185);
FORCEPROP 1 LASTPIN (-6325 3175) BN 16
J 0
(-6337 3183);
DISPLAY 0.489362 (-6337 3183);
PAINT GREEN (-6337 3183);
FORCEPROP 2 LAST CDS_LIB mstr_standard
J 0
(-6275 3175);
DISPLAY 0.723404 (-6275 3175);
PAINT MONO (-6275 3175);
DISPLAY INVISIBLE (-6275 3175);
FORCEPROP 1 LAST BODY_TYPE PLUMBING
J 0
(-6275 3225);
DISPLAY 0.872340 (-6275 3225);
PAINT GREEN (-6275 3225);
DISPLAY INVISIBLE (-6275 3225);
FORCEPROP 1 LAST HDL_TAP TRUE
J 0
(-5950 3050);
DISPLAY 0.872340 (-5950 3050);
DISPLAY INVISIBLE (-5950 3050);
FORCEPROP 1 LAST PATH I225
J 0
(-6277 3175);
DISPLAY 0.872340 (-6277 3175);
PAINT GREEN (-6277 3175);
DISPLAY INVISIBLE (-6277 3175);
FORCEADD TAP..1
(-6275 3425);
FORCEPROP 3 LASTPIN (-6325 3425) SIG_NAME M_E_CPU0_SB_DQ<21>
J 0
(-6315 3435);
DISPLAY 0.659574 (-6315 3435);
PAINT MONO (-6315 3435);
DISPLAY INVISIBLE (-6315 3435);
FORCEPROP 1 LASTPIN (-6325 3425) BN 21
J 0
(-6337 3433);
DISPLAY 0.489362 (-6337 3433);
PAINT GREEN (-6337 3433);
FORCEPROP 2 LAST CDS_LIB mstr_standard
J 0
(-6275 3425);
DISPLAY 0.723404 (-6275 3425);
PAINT MONO (-6275 3425);
DISPLAY INVISIBLE (-6275 3425);
FORCEPROP 1 LAST BODY_TYPE PLUMBING
J 0
(-6275 3475);
DISPLAY 0.872340 (-6275 3475);
PAINT GREEN (-6275 3475);
DISPLAY INVISIBLE (-6275 3475);
FORCEPROP 1 LAST HDL_TAP TRUE
J 0
(-5950 3300);
DISPLAY 0.872340 (-5950 3300);
DISPLAY INVISIBLE (-5950 3300);
FORCEPROP 1 LAST PATH I226
J 0
(-6277 3425);
DISPLAY 0.872340 (-6277 3425);
PAINT GREEN (-6277 3425);
DISPLAY INVISIBLE (-6277 3425);
FORCEADD TAP..1
(-6275 3475);
FORCEPROP 3 LASTPIN (-6325 3475) SIG_NAME M_E_CPU0_SB_DQ<22>
J 0
(-6315 3485);
DISPLAY 0.659574 (-6315 3485);
PAINT MONO (-6315 3485);
DISPLAY INVISIBLE (-6315 3485);
FORCEPROP 1 LASTPIN (-6325 3475) BN 22
J 0
(-6337 3483);
DISPLAY 0.489362 (-6337 3483);
PAINT GREEN (-6337 3483);
FORCEPROP 2 LAST CDS_LIB mstr_standard
J 0
(-6275 3475);
DISPLAY 0.723404 (-6275 3475);
PAINT MONO (-6275 3475);
DISPLAY INVISIBLE (-6275 3475);
FORCEPROP 1 LAST BODY_TYPE PLUMBING
J 0
(-6275 3525);
DISPLAY 0.872340 (-6275 3525);
PAINT GREEN (-6275 3525);
DISPLAY INVISIBLE (-6275 3525);
FORCEPROP 1 LAST HDL_TAP TRUE
J 0
(-5950 3350);
DISPLAY 0.872340 (-5950 3350);
DISPLAY INVISIBLE (-5950 3350);
FORCEPROP 1 LAST PATH I227
J 0
(-6277 3475);
DISPLAY 0.872340 (-6277 3475);
PAINT GREEN (-6277 3475);
DISPLAY INVISIBLE (-6277 3475);
FORCEADD TAP..1
(-6275 3375);
FORCEPROP 3 LASTPIN (-6325 3375) SIG_NAME M_E_CPU0_SB_DQ<20>
J 0
(-6315 3385);
DISPLAY 0.659574 (-6315 3385);
PAINT MONO (-6315 3385);
DISPLAY INVISIBLE (-6315 3385);
FORCEPROP 1 LASTPIN (-6325 3375) BN 20
J 0
(-6337 3383);
DISPLAY 0.489362 (-6337 3383);
PAINT GREEN (-6337 3383);
FORCEPROP 2 LAST CDS_LIB mstr_standard
J 0
(-6275 3375);
DISPLAY 0.723404 (-6275 3375);
PAINT MONO (-6275 3375);
DISPLAY INVISIBLE (-6275 3375);
FORCEPROP 1 LAST BODY_TYPE PLUMBING
J 0
(-6275 3425);
DISPLAY 0.872340 (-6275 3425);
PAINT GREEN (-6275 3425);
DISPLAY INVISIBLE (-6275 3425);
FORCEPROP 1 LAST HDL_TAP TRUE
J 0
(-5950 3250);
DISPLAY 0.872340 (-5950 3250);
DISPLAY INVISIBLE (-5950 3250);
FORCEPROP 1 LAST PATH I228
J 0
(-6277 3375);
DISPLAY 0.872340 (-6277 3375);
PAINT GREEN (-6277 3375);
DISPLAY INVISIBLE (-6277 3375);
FORCEADD TAP..1
(-6275 3525);
FORCEPROP 3 LASTPIN (-6325 3525) SIG_NAME M_E_CPU0_SB_DQ<23>
J 0
(-6315 3535);
DISPLAY 0.659574 (-6315 3535);
PAINT MONO (-6315 3535);
DISPLAY INVISIBLE (-6315 3535);
FORCEPROP 1 LASTPIN (-6325 3525) BN 23
J 0
(-6337 3533);
DISPLAY 0.489362 (-6337 3533);
PAINT GREEN (-6337 3533);
FORCEPROP 2 LAST CDS_LIB mstr_standard
J 0
(-6275 3525);
DISPLAY 0.723404 (-6275 3525);
PAINT MONO (-6275 3525);
DISPLAY INVISIBLE (-6275 3525);
FORCEPROP 1 LAST BODY_TYPE PLUMBING
J 0
(-6275 3575);
DISPLAY 0.872340 (-6275 3575);
PAINT GREEN (-6275 3575);
DISPLAY INVISIBLE (-6275 3575);
FORCEPROP 1 LAST HDL_TAP TRUE
J 0
(-5950 3400);
DISPLAY 0.872340 (-5950 3400);
DISPLAY INVISIBLE (-5950 3400);
FORCEPROP 1 LAST PATH I229
J 0
(-6277 3525);
DISPLAY 0.872340 (-6277 3525);
PAINT GREEN (-6277 3525);
DISPLAY INVISIBLE (-6277 3525);
FORCEADD TAP..1
(-6275 3325);
FORCEPROP 3 LASTPIN (-6325 3325) SIG_NAME M_E_CPU0_SB_DQ<19>
J 0
(-6315 3335);
DISPLAY 0.659574 (-6315 3335);
PAINT MONO (-6315 3335);
DISPLAY INVISIBLE (-6315 3335);
FORCEPROP 1 LASTPIN (-6325 3325) BN 19
J 0
(-6337 3333);
DISPLAY 0.489362 (-6337 3333);
PAINT GREEN (-6337 3333);
FORCEPROP 2 LAST CDS_LIB mstr_standard
J 0
(-6275 3325);
DISPLAY 0.723404 (-6275 3325);
PAINT MONO (-6275 3325);
DISPLAY INVISIBLE (-6275 3325);
FORCEPROP 1 LAST BODY_TYPE PLUMBING
J 0
(-6275 3375);
DISPLAY 0.872340 (-6275 3375);
PAINT GREEN (-6275 3375);
DISPLAY INVISIBLE (-6275 3375);
FORCEPROP 1 LAST HDL_TAP TRUE
J 0
(-5950 3200);
DISPLAY 0.872340 (-5950 3200);
DISPLAY INVISIBLE (-5950 3200);
FORCEPROP 1 LAST PATH I230
J 0
(-6277 3325);
DISPLAY 0.872340 (-6277 3325);
PAINT GREEN (-6277 3325);
DISPLAY INVISIBLE (-6277 3325);
FORCEADD TAP..1
(-6275 3675);
FORCEPROP 3 LASTPIN (-6325 3675) SIG_NAME M_E_CPU0_SB_DQ<26>
J 0
(-6315 3685);
DISPLAY 0.659574 (-6315 3685);
PAINT MONO (-6315 3685);
DISPLAY INVISIBLE (-6315 3685);
FORCEPROP 1 LASTPIN (-6325 3675) BN 26
J 0
(-6337 3683);
DISPLAY 0.489362 (-6337 3683);
PAINT GREEN (-6337 3683);
FORCEPROP 2 LAST CDS_LIB mstr_standard
J 0
(-6275 3675);
DISPLAY 0.723404 (-6275 3675);
PAINT MONO (-6275 3675);
DISPLAY INVISIBLE (-6275 3675);
FORCEPROP 1 LAST BODY_TYPE PLUMBING
J 0
(-6275 3725);
DISPLAY 0.872340 (-6275 3725);
PAINT GREEN (-6275 3725);
DISPLAY INVISIBLE (-6275 3725);
FORCEPROP 1 LAST HDL_TAP TRUE
J 0
(-5950 3550);
DISPLAY 0.872340 (-5950 3550);
DISPLAY INVISIBLE (-5950 3550);
FORCEPROP 1 LAST PATH I231
J 0
(-6277 3675);
DISPLAY 0.872340 (-6277 3675);
PAINT GREEN (-6277 3675);
DISPLAY INVISIBLE (-6277 3675);
FORCEADD TAP..1
(-6275 3725);
FORCEPROP 3 LASTPIN (-6325 3725) SIG_NAME M_E_CPU0_SB_DQ<27>
J 0
(-6315 3735);
DISPLAY 0.659574 (-6315 3735);
PAINT MONO (-6315 3735);
DISPLAY INVISIBLE (-6315 3735);
FORCEPROP 1 LASTPIN (-6325 3725) BN 27
J 0
(-6337 3733);
DISPLAY 0.489362 (-6337 3733);
PAINT GREEN (-6337 3733);
FORCEPROP 2 LAST CDS_LIB mstr_standard
J 0
(-6275 3725);
DISPLAY 0.723404 (-6275 3725);
PAINT MONO (-6275 3725);
DISPLAY INVISIBLE (-6275 3725);
FORCEPROP 1 LAST BODY_TYPE PLUMBING
J 0
(-6275 3775);
DISPLAY 0.872340 (-6275 3775);
PAINT GREEN (-6275 3775);
DISPLAY INVISIBLE (-6275 3775);
FORCEPROP 1 LAST HDL_TAP TRUE
J 0
(-5950 3600);
DISPLAY 0.872340 (-5950 3600);
DISPLAY INVISIBLE (-5950 3600);
FORCEPROP 1 LAST PATH I232
J 0
(-6277 3725);
DISPLAY 0.872340 (-6277 3725);
PAINT GREEN (-6277 3725);
DISPLAY INVISIBLE (-6277 3725);
FORCEADD TAP..1
(-6275 3625);
FORCEPROP 3 LASTPIN (-6325 3625) SIG_NAME M_E_CPU0_SB_DQ<25>
J 0
(-6315 3635);
DISPLAY 0.659574 (-6315 3635);
PAINT MONO (-6315 3635);
DISPLAY INVISIBLE (-6315 3635);
FORCEPROP 1 LASTPIN (-6325 3625) BN 25
J 0
(-6337 3633);
DISPLAY 0.489362 (-6337 3633);
PAINT GREEN (-6337 3633);
FORCEPROP 2 LAST CDS_LIB mstr_standard
J 0
(-6275 3625);
DISPLAY 0.723404 (-6275 3625);
PAINT MONO (-6275 3625);
DISPLAY INVISIBLE (-6275 3625);
FORCEPROP 1 LAST BODY_TYPE PLUMBING
J 0
(-6275 3675);
DISPLAY 0.872340 (-6275 3675);
PAINT GREEN (-6275 3675);
DISPLAY INVISIBLE (-6275 3675);
FORCEPROP 1 LAST HDL_TAP TRUE
J 0
(-5950 3500);
DISPLAY 0.872340 (-5950 3500);
DISPLAY INVISIBLE (-5950 3500);
FORCEPROP 1 LAST PATH I233
J 0
(-6277 3625);
DISPLAY 0.872340 (-6277 3625);
PAINT GREEN (-6277 3625);
DISPLAY INVISIBLE (-6277 3625);
FORCEADD TAP..1
(-6275 3775);
FORCEPROP 3 LASTPIN (-6325 3775) SIG_NAME M_E_CPU0_SB_DQ<28>
J 0
(-6315 3785);
DISPLAY 0.659574 (-6315 3785);
PAINT MONO (-6315 3785);
DISPLAY INVISIBLE (-6315 3785);
FORCEPROP 1 LASTPIN (-6325 3775) BN 28
J 0
(-6337 3783);
DISPLAY 0.489362 (-6337 3783);
PAINT GREEN (-6337 3783);
FORCEPROP 2 LAST CDS_LIB mstr_standard
J 0
(-6275 3775);
DISPLAY 0.723404 (-6275 3775);
PAINT MONO (-6275 3775);
DISPLAY INVISIBLE (-6275 3775);
FORCEPROP 1 LAST BODY_TYPE PLUMBING
J 0
(-6275 3825);
DISPLAY 0.872340 (-6275 3825);
PAINT GREEN (-6275 3825);
DISPLAY INVISIBLE (-6275 3825);
FORCEPROP 1 LAST HDL_TAP TRUE
J 0
(-5950 3650);
DISPLAY 0.872340 (-5950 3650);
DISPLAY INVISIBLE (-5950 3650);
FORCEPROP 1 LAST PATH I234
J 0
(-6277 3775);
DISPLAY 0.872340 (-6277 3775);
PAINT GREEN (-6277 3775);
DISPLAY INVISIBLE (-6277 3775);
FORCEADD TAP..1
(-6275 3575);
FORCEPROP 3 LASTPIN (-6325 3575) SIG_NAME M_E_CPU0_SB_DQ<24>
J 0
(-6315 3585);
DISPLAY 0.659574 (-6315 3585);
PAINT MONO (-6315 3585);
DISPLAY INVISIBLE (-6315 3585);
FORCEPROP 1 LASTPIN (-6325 3575) BN 24
J 0
(-6337 3583);
DISPLAY 0.489362 (-6337 3583);
PAINT GREEN (-6337 3583);
FORCEPROP 2 LAST CDS_LIB mstr_standard
J 0
(-6275 3575);
DISPLAY 0.723404 (-6275 3575);
PAINT MONO (-6275 3575);
DISPLAY INVISIBLE (-6275 3575);
FORCEPROP 1 LAST BODY_TYPE PLUMBING
J 0
(-6275 3625);
DISPLAY 0.872340 (-6275 3625);
PAINT GREEN (-6275 3625);
DISPLAY INVISIBLE (-6275 3625);
FORCEPROP 1 LAST HDL_TAP TRUE
J 0
(-5950 3450);
DISPLAY 0.872340 (-5950 3450);
DISPLAY INVISIBLE (-5950 3450);
FORCEPROP 1 LAST PATH I235
J 0
(-6277 3575);
DISPLAY 0.872340 (-6277 3575);
PAINT GREEN (-6277 3575);
DISPLAY INVISIBLE (-6277 3575);
FORCEADD TAP..1
(-6275 4025);
FORCEPROP 3 LASTPIN (-6325 4025) SIG_NAME M_E_CPU0_SA_DQ<0>
J 0
(-6315 4035);
DISPLAY 0.659574 (-6315 4035);
PAINT MONO (-6315 4035);
DISPLAY INVISIBLE (-6315 4035);
FORCEPROP 1 LASTPIN (-6325 4025) BN 0
J 0
(-6337 4033);
DISPLAY 0.489362 (-6337 4033);
PAINT GREEN (-6337 4033);
FORCEPROP 2 LAST CDS_LIB mstr_standard
J 0
(-6275 4025);
DISPLAY 0.723404 (-6275 4025);
PAINT MONO (-6275 4025);
DISPLAY INVISIBLE (-6275 4025);
FORCEPROP 1 LAST BODY_TYPE PLUMBING
J 0
(-6275 4075);
DISPLAY 0.872340 (-6275 4075);
PAINT GREEN (-6275 4075);
DISPLAY INVISIBLE (-6275 4075);
FORCEPROP 1 LAST HDL_TAP TRUE
J 0
(-5950 3900);
DISPLAY 0.872340 (-5950 3900);
DISPLAY INVISIBLE (-5950 3900);
FORCEPROP 1 LAST PATH I236
J 0
(-6277 4025);
DISPLAY 0.872340 (-6277 4025);
PAINT GREEN (-6277 4025);
DISPLAY INVISIBLE (-6277 4025);
FORCEADD TAP..1
(-6275 3875);
FORCEPROP 3 LASTPIN (-6325 3875) SIG_NAME M_E_CPU0_SB_DQ<30>
J 0
(-6315 3885);
DISPLAY 0.659574 (-6315 3885);
PAINT MONO (-6315 3885);
DISPLAY INVISIBLE (-6315 3885);
FORCEPROP 1 LASTPIN (-6325 3875) BN 30
J 0
(-6337 3883);
DISPLAY 0.489362 (-6337 3883);
PAINT GREEN (-6337 3883);
FORCEPROP 2 LAST CDS_LIB mstr_standard
J 0
(-6275 3875);
DISPLAY 0.723404 (-6275 3875);
PAINT MONO (-6275 3875);
DISPLAY INVISIBLE (-6275 3875);
FORCEPROP 1 LAST BODY_TYPE PLUMBING
J 0
(-6275 3925);
DISPLAY 0.872340 (-6275 3925);
PAINT GREEN (-6275 3925);
DISPLAY INVISIBLE (-6275 3925);
FORCEPROP 1 LAST HDL_TAP TRUE
J 0
(-5950 3750);
DISPLAY 0.872340 (-5950 3750);
DISPLAY INVISIBLE (-5950 3750);
FORCEPROP 1 LAST PATH I237
J 0
(-6277 3875);
DISPLAY 0.872340 (-6277 3875);
PAINT GREEN (-6277 3875);
DISPLAY INVISIBLE (-6277 3875);
FORCEADD TAP..1
(-6275 3925);
FORCEPROP 3 LASTPIN (-6325 3925) SIG_NAME M_E_CPU0_SB_DQ<31>
J 0
(-6315 3935);
DISPLAY 0.659574 (-6315 3935);
PAINT MONO (-6315 3935);
DISPLAY INVISIBLE (-6315 3935);
FORCEPROP 1 LASTPIN (-6325 3925) BN 31
J 0
(-6337 3933);
DISPLAY 0.489362 (-6337 3933);
PAINT GREEN (-6337 3933);
FORCEPROP 2 LAST CDS_LIB mstr_standard
J 0
(-6275 3925);
DISPLAY 0.723404 (-6275 3925);
PAINT MONO (-6275 3925);
DISPLAY INVISIBLE (-6275 3925);
FORCEPROP 1 LAST BODY_TYPE PLUMBING
J 0
(-6275 3975);
DISPLAY 0.872340 (-6275 3975);
PAINT GREEN (-6275 3975);
DISPLAY INVISIBLE (-6275 3975);
FORCEPROP 1 LAST HDL_TAP TRUE
J 0
(-5950 3800);
DISPLAY 0.872340 (-5950 3800);
DISPLAY INVISIBLE (-5950 3800);
FORCEPROP 1 LAST PATH I238
J 0
(-6277 3925);
DISPLAY 0.872340 (-6277 3925);
PAINT GREEN (-6277 3925);
DISPLAY INVISIBLE (-6277 3925);
FORCEADD TAP..1
(-6275 3825);
FORCEPROP 3 LASTPIN (-6325 3825) SIG_NAME M_E_CPU0_SB_DQ<29>
J 0
(-6315 3835);
DISPLAY 0.659574 (-6315 3835);
PAINT MONO (-6315 3835);
DISPLAY INVISIBLE (-6315 3835);
FORCEPROP 1 LASTPIN (-6325 3825) BN 29
J 0
(-6337 3833);
DISPLAY 0.489362 (-6337 3833);
PAINT GREEN (-6337 3833);
FORCEPROP 2 LAST CDS_LIB mstr_standard
J 0
(-6275 3825);
DISPLAY 0.723404 (-6275 3825);
PAINT MONO (-6275 3825);
DISPLAY INVISIBLE (-6275 3825);
FORCEPROP 1 LAST BODY_TYPE PLUMBING
J 0
(-6275 3875);
DISPLAY 0.872340 (-6275 3875);
PAINT GREEN (-6275 3875);
DISPLAY INVISIBLE (-6275 3875);
FORCEPROP 1 LAST HDL_TAP TRUE
J 0
(-5950 3700);
DISPLAY 0.872340 (-5950 3700);
DISPLAY INVISIBLE (-5950 3700);
FORCEPROP 1 LAST PATH I239
J 0
(-6277 3825);
DISPLAY 0.872340 (-6277 3825);
PAINT GREEN (-6277 3825);
DISPLAY INVISIBLE (-6277 3825);
FORCEADD TAP..1
(-6275 4125);
FORCEPROP 3 LASTPIN (-6325 4125) SIG_NAME M_E_CPU0_SA_DQ<2>
J 0
(-6315 4135);
DISPLAY 0.659574 (-6315 4135);
PAINT MONO (-6315 4135);
DISPLAY INVISIBLE (-6315 4135);
FORCEPROP 1 LASTPIN (-6325 4125) BN 2
J 0
(-6337 4133);
DISPLAY 0.489362 (-6337 4133);
PAINT GREEN (-6337 4133);
FORCEPROP 2 LAST CDS_LIB mstr_standard
J 0
(-6275 4125);
DISPLAY 0.723404 (-6275 4125);
PAINT MONO (-6275 4125);
DISPLAY INVISIBLE (-6275 4125);
FORCEPROP 1 LAST BODY_TYPE PLUMBING
J 0
(-6275 4175);
DISPLAY 0.872340 (-6275 4175);
PAINT GREEN (-6275 4175);
DISPLAY INVISIBLE (-6275 4175);
FORCEPROP 1 LAST HDL_TAP TRUE
J 0
(-5950 4000);
DISPLAY 0.872340 (-5950 4000);
DISPLAY INVISIBLE (-5950 4000);
FORCEPROP 1 LAST PATH I240
J 0
(-6277 4125);
DISPLAY 0.872340 (-6277 4125);
PAINT GREEN (-6277 4125);
DISPLAY INVISIBLE (-6277 4125);
FORCEADD TAP..1
(-6275 4075);
FORCEPROP 3 LASTPIN (-6325 4075) SIG_NAME M_E_CPU0_SA_DQ<1>
J 0
(-6315 4085);
DISPLAY 0.659574 (-6315 4085);
PAINT MONO (-6315 4085);
DISPLAY INVISIBLE (-6315 4085);
FORCEPROP 1 LASTPIN (-6325 4075) BN 1
J 0
(-6337 4083);
DISPLAY 0.489362 (-6337 4083);
PAINT GREEN (-6337 4083);
FORCEPROP 2 LAST CDS_LIB mstr_standard
J 0
(-6275 4075);
DISPLAY 0.723404 (-6275 4075);
PAINT MONO (-6275 4075);
DISPLAY INVISIBLE (-6275 4075);
FORCEPROP 1 LAST BODY_TYPE PLUMBING
J 0
(-6275 4125);
DISPLAY 0.872340 (-6275 4125);
PAINT GREEN (-6275 4125);
DISPLAY INVISIBLE (-6275 4125);
FORCEPROP 1 LAST HDL_TAP TRUE
J 0
(-5950 3950);
DISPLAY 0.872340 (-5950 3950);
DISPLAY INVISIBLE (-5950 3950);
FORCEPROP 1 LAST PATH I241
J 0
(-6277 4075);
DISPLAY 0.872340 (-6277 4075);
PAINT GREEN (-6277 4075);
DISPLAY INVISIBLE (-6277 4075);
FORCEADD TAP..1
(-6275 4175);
FORCEPROP 3 LASTPIN (-6325 4175) SIG_NAME M_E_CPU0_SA_DQ<3>
J 0
(-6315 4185);
DISPLAY 0.659574 (-6315 4185);
PAINT MONO (-6315 4185);
DISPLAY INVISIBLE (-6315 4185);
FORCEPROP 1 LASTPIN (-6325 4175) BN 3
J 0
(-6337 4183);
DISPLAY 0.489362 (-6337 4183);
PAINT GREEN (-6337 4183);
FORCEPROP 2 LAST CDS_LIB mstr_standard
J 0
(-6275 4175);
DISPLAY 0.723404 (-6275 4175);
PAINT MONO (-6275 4175);
DISPLAY INVISIBLE (-6275 4175);
FORCEPROP 1 LAST BODY_TYPE PLUMBING
J 0
(-6275 4225);
DISPLAY 0.872340 (-6275 4225);
PAINT GREEN (-6275 4225);
DISPLAY INVISIBLE (-6275 4225);
FORCEPROP 1 LAST HDL_TAP TRUE
J 0
(-5950 4050);
DISPLAY 0.872340 (-5950 4050);
DISPLAY INVISIBLE (-5950 4050);
FORCEPROP 1 LAST PATH I242
J 0
(-6277 4175);
DISPLAY 0.872340 (-6277 4175);
PAINT GREEN (-6277 4175);
DISPLAY INVISIBLE (-6277 4175);
FORCEADD TAP..1
(-6275 4225);
FORCEPROP 3 LASTPIN (-6325 4225) SIG_NAME M_E_CPU0_SA_DQ<4>
J 0
(-6315 4235);
DISPLAY 0.659574 (-6315 4235);
PAINT MONO (-6315 4235);
DISPLAY INVISIBLE (-6315 4235);
FORCEPROP 1 LASTPIN (-6325 4225) BN 4
J 0
(-6337 4233);
DISPLAY 0.489362 (-6337 4233);
PAINT GREEN (-6337 4233);
FORCEPROP 2 LAST CDS_LIB mstr_standard
J 0
(-6275 4225);
DISPLAY 0.723404 (-6275 4225);
PAINT MONO (-6275 4225);
DISPLAY INVISIBLE (-6275 4225);
FORCEPROP 1 LAST BODY_TYPE PLUMBING
J 0
(-6275 4275);
DISPLAY 0.872340 (-6275 4275);
PAINT GREEN (-6275 4275);
DISPLAY INVISIBLE (-6275 4275);
FORCEPROP 1 LAST HDL_TAP TRUE
J 0
(-5950 4100);
DISPLAY 0.872340 (-5950 4100);
DISPLAY INVISIBLE (-5950 4100);
FORCEPROP 1 LAST PATH I243
J 0
(-6277 4225);
DISPLAY 0.872340 (-6277 4225);
PAINT GREEN (-6277 4225);
DISPLAY INVISIBLE (-6277 4225);
FORCEADD TAP..1
(-6275 4275);
FORCEPROP 3 LASTPIN (-6325 4275) SIG_NAME M_E_CPU0_SA_DQ<5>
J 0
(-6315 4285);
DISPLAY 0.659574 (-6315 4285);
PAINT MONO (-6315 4285);
DISPLAY INVISIBLE (-6315 4285);
FORCEPROP 1 LASTPIN (-6325 4275) BN 5
J 0
(-6337 4283);
DISPLAY 0.489362 (-6337 4283);
PAINT GREEN (-6337 4283);
FORCEPROP 2 LAST CDS_LIB mstr_standard
J 0
(-6275 4275);
DISPLAY 0.723404 (-6275 4275);
PAINT MONO (-6275 4275);
DISPLAY INVISIBLE (-6275 4275);
FORCEPROP 1 LAST BODY_TYPE PLUMBING
J 0
(-6275 4325);
DISPLAY 0.872340 (-6275 4325);
PAINT GREEN (-6275 4325);
DISPLAY INVISIBLE (-6275 4325);
FORCEPROP 1 LAST HDL_TAP TRUE
J 0
(-5950 4150);
DISPLAY 0.872340 (-5950 4150);
DISPLAY INVISIBLE (-5950 4150);
FORCEPROP 1 LAST PATH I244
J 0
(-6277 4275);
DISPLAY 0.872340 (-6277 4275);
PAINT GREEN (-6277 4275);
DISPLAY INVISIBLE (-6277 4275);
FORCEADD TAP..1
(-6275 4375);
FORCEPROP 3 LASTPIN (-6325 4375) SIG_NAME M_E_CPU0_SA_DQ<7>
J 0
(-6315 4385);
DISPLAY 0.659574 (-6315 4385);
PAINT MONO (-6315 4385);
DISPLAY INVISIBLE (-6315 4385);
FORCEPROP 1 LASTPIN (-6325 4375) BN 7
J 0
(-6337 4383);
DISPLAY 0.489362 (-6337 4383);
PAINT GREEN (-6337 4383);
FORCEPROP 2 LAST CDS_LIB mstr_standard
J 0
(-6275 4375);
DISPLAY 0.723404 (-6275 4375);
PAINT MONO (-6275 4375);
DISPLAY INVISIBLE (-6275 4375);
FORCEPROP 1 LAST BODY_TYPE PLUMBING
J 0
(-6275 4425);
DISPLAY 0.872340 (-6275 4425);
PAINT GREEN (-6275 4425);
DISPLAY INVISIBLE (-6275 4425);
FORCEPROP 1 LAST HDL_TAP TRUE
J 0
(-5950 4250);
DISPLAY 0.872340 (-5950 4250);
DISPLAY INVISIBLE (-5950 4250);
FORCEPROP 1 LAST PATH I245
J 0
(-6277 4375);
DISPLAY 0.872340 (-6277 4375);
PAINT GREEN (-6277 4375);
DISPLAY INVISIBLE (-6277 4375);
FORCEADD TAP..1
(-6275 4325);
FORCEPROP 3 LASTPIN (-6325 4325) SIG_NAME M_E_CPU0_SA_DQ<6>
J 0
(-6315 4335);
DISPLAY 0.659574 (-6315 4335);
PAINT MONO (-6315 4335);
DISPLAY INVISIBLE (-6315 4335);
FORCEPROP 1 LASTPIN (-6325 4325) BN 6
J 0
(-6337 4333);
DISPLAY 0.489362 (-6337 4333);
PAINT GREEN (-6337 4333);
FORCEPROP 2 LAST CDS_LIB mstr_standard
J 0
(-6275 4325);
DISPLAY 0.723404 (-6275 4325);
PAINT MONO (-6275 4325);
DISPLAY INVISIBLE (-6275 4325);
FORCEPROP 1 LAST BODY_TYPE PLUMBING
J 0
(-6275 4375);
DISPLAY 0.872340 (-6275 4375);
PAINT GREEN (-6275 4375);
DISPLAY INVISIBLE (-6275 4375);
FORCEPROP 1 LAST HDL_TAP TRUE
J 0
(-5950 4200);
DISPLAY 0.872340 (-5950 4200);
DISPLAY INVISIBLE (-5950 4200);
FORCEPROP 1 LAST PATH I246
J 0
(-6277 4325);
DISPLAY 0.872340 (-6277 4325);
PAINT GREEN (-6277 4325);
DISPLAY INVISIBLE (-6277 4325);
FORCEADD TAP..1
(-6275 4425);
FORCEPROP 3 LASTPIN (-6325 4425) SIG_NAME M_E_CPU0_SA_DQ<8>
J 0
(-6315 4435);
DISPLAY 0.659574 (-6315 4435);
PAINT MONO (-6315 4435);
DISPLAY INVISIBLE (-6315 4435);
FORCEPROP 1 LASTPIN (-6325 4425) BN 8
J 0
(-6337 4433);
DISPLAY 0.489362 (-6337 4433);
PAINT GREEN (-6337 4433);
FORCEPROP 2 LAST CDS_LIB mstr_standard
J 0
(-6275 4425);
DISPLAY 0.723404 (-6275 4425);
PAINT MONO (-6275 4425);
DISPLAY INVISIBLE (-6275 4425);
FORCEPROP 1 LAST BODY_TYPE PLUMBING
J 0
(-6275 4475);
DISPLAY 0.872340 (-6275 4475);
PAINT GREEN (-6275 4475);
DISPLAY INVISIBLE (-6275 4475);
FORCEPROP 1 LAST HDL_TAP TRUE
J 0
(-5950 4300);
DISPLAY 0.872340 (-5950 4300);
DISPLAY INVISIBLE (-5950 4300);
FORCEPROP 1 LAST PATH I247
J 0
(-6277 4425);
DISPLAY 0.872340 (-6277 4425);
PAINT GREEN (-6277 4425);
DISPLAY INVISIBLE (-6277 4425);
FORCEADD TAP..1
(-6275 4475);
FORCEPROP 3 LASTPIN (-6325 4475) SIG_NAME M_E_CPU0_SA_DQ<9>
J 0
(-6315 4485);
DISPLAY 0.659574 (-6315 4485);
PAINT MONO (-6315 4485);
DISPLAY INVISIBLE (-6315 4485);
FORCEPROP 1 LASTPIN (-6325 4475) BN 9
J 0
(-6337 4483);
DISPLAY 0.489362 (-6337 4483);
PAINT GREEN (-6337 4483);
FORCEPROP 2 LAST CDS_LIB mstr_standard
J 0
(-6275 4475);
DISPLAY 0.723404 (-6275 4475);
PAINT MONO (-6275 4475);
DISPLAY INVISIBLE (-6275 4475);
FORCEPROP 1 LAST BODY_TYPE PLUMBING
J 0
(-6275 4525);
DISPLAY 0.872340 (-6275 4525);
PAINT GREEN (-6275 4525);
DISPLAY INVISIBLE (-6275 4525);
FORCEPROP 1 LAST HDL_TAP TRUE
J 0
(-5950 4350);
DISPLAY 0.872340 (-5950 4350);
DISPLAY INVISIBLE (-5950 4350);
FORCEPROP 1 LAST PATH I248
J 0
(-6277 4475);
DISPLAY 0.872340 (-6277 4475);
PAINT GREEN (-6277 4475);
DISPLAY INVISIBLE (-6277 4475);
FORCEADD TAP..1
(-6275 4525);
FORCEPROP 3 LASTPIN (-6325 4525) SIG_NAME M_E_CPU0_SA_DQ<10>
J 0
(-6315 4535);
DISPLAY 0.659574 (-6315 4535);
PAINT MONO (-6315 4535);
DISPLAY INVISIBLE (-6315 4535);
FORCEPROP 1 LASTPIN (-6325 4525) BN 10
J 0
(-6337 4533);
DISPLAY 0.489362 (-6337 4533);
PAINT GREEN (-6337 4533);
FORCEPROP 2 LAST CDS_LIB mstr_standard
J 0
(-6275 4525);
DISPLAY 0.723404 (-6275 4525);
PAINT MONO (-6275 4525);
DISPLAY INVISIBLE (-6275 4525);
FORCEPROP 1 LAST BODY_TYPE PLUMBING
J 0
(-6275 4575);
DISPLAY 0.872340 (-6275 4575);
PAINT GREEN (-6275 4575);
DISPLAY INVISIBLE (-6275 4575);
FORCEPROP 1 LAST HDL_TAP TRUE
J 0
(-5950 4400);
DISPLAY 0.872340 (-5950 4400);
DISPLAY INVISIBLE (-5950 4400);
FORCEPROP 1 LAST PATH I249
J 0
(-6277 4525);
DISPLAY 0.872340 (-6277 4525);
PAINT GREEN (-6277 4525);
DISPLAY INVISIBLE (-6277 4525);
FORCEADD TAP..1
(-6275 4725);
FORCEPROP 3 LASTPIN (-6325 4725) SIG_NAME M_E_CPU0_SA_DQ<14>
J 0
(-6315 4735);
DISPLAY 0.659574 (-6315 4735);
PAINT MONO (-6315 4735);
DISPLAY INVISIBLE (-6315 4735);
FORCEPROP 1 LASTPIN (-6325 4725) BN 14
J 0
(-6337 4733);
DISPLAY 0.489362 (-6337 4733);
PAINT GREEN (-6337 4733);
FORCEPROP 2 LAST CDS_LIB mstr_standard
J 0
(-6275 4725);
DISPLAY 0.723404 (-6275 4725);
PAINT MONO (-6275 4725);
DISPLAY INVISIBLE (-6275 4725);
FORCEPROP 1 LAST BODY_TYPE PLUMBING
J 0
(-6275 4775);
DISPLAY 0.872340 (-6275 4775);
PAINT GREEN (-6275 4775);
DISPLAY INVISIBLE (-6275 4775);
FORCEPROP 1 LAST HDL_TAP TRUE
J 0
(-5950 4600);
DISPLAY 0.872340 (-5950 4600);
DISPLAY INVISIBLE (-5950 4600);
FORCEPROP 1 LAST PATH I250
J 0
(-6277 4725);
DISPLAY 0.872340 (-6277 4725);
PAINT GREEN (-6277 4725);
DISPLAY INVISIBLE (-6277 4725);
FORCEADD TAP..1
(-6275 4775);
FORCEPROP 3 LASTPIN (-6325 4775) SIG_NAME M_E_CPU0_SA_DQ<15>
J 0
(-6315 4785);
DISPLAY 0.659574 (-6315 4785);
PAINT MONO (-6315 4785);
DISPLAY INVISIBLE (-6315 4785);
FORCEPROP 1 LASTPIN (-6325 4775) BN 15
J 0
(-6337 4783);
DISPLAY 0.489362 (-6337 4783);
PAINT GREEN (-6337 4783);
FORCEPROP 2 LAST CDS_LIB mstr_standard
J 0
(-6275 4775);
DISPLAY 0.723404 (-6275 4775);
PAINT MONO (-6275 4775);
DISPLAY INVISIBLE (-6275 4775);
FORCEPROP 1 LAST BODY_TYPE PLUMBING
J 0
(-6275 4825);
DISPLAY 0.872340 (-6275 4825);
PAINT GREEN (-6275 4825);
DISPLAY INVISIBLE (-6275 4825);
FORCEPROP 1 LAST HDL_TAP TRUE
J 0
(-5950 4650);
DISPLAY 0.872340 (-5950 4650);
DISPLAY INVISIBLE (-5950 4650);
FORCEPROP 1 LAST PATH I251
J 0
(-6277 4775);
DISPLAY 0.872340 (-6277 4775);
PAINT GREEN (-6277 4775);
DISPLAY INVISIBLE (-6277 4775);
FORCEADD TAP..1
(-6275 4675);
FORCEPROP 3 LASTPIN (-6325 4675) SIG_NAME M_E_CPU0_SA_DQ<13>
J 0
(-6315 4685);
DISPLAY 0.659574 (-6315 4685);
PAINT MONO (-6315 4685);
DISPLAY INVISIBLE (-6315 4685);
FORCEPROP 1 LASTPIN (-6325 4675) BN 13
J 0
(-6337 4683);
DISPLAY 0.489362 (-6337 4683);
PAINT GREEN (-6337 4683);
FORCEPROP 2 LAST CDS_LIB mstr_standard
J 0
(-6275 4675);
DISPLAY 0.723404 (-6275 4675);
PAINT MONO (-6275 4675);
DISPLAY INVISIBLE (-6275 4675);
FORCEPROP 1 LAST BODY_TYPE PLUMBING
J 0
(-6275 4725);
DISPLAY 0.872340 (-6275 4725);
PAINT GREEN (-6275 4725);
DISPLAY INVISIBLE (-6275 4725);
FORCEPROP 1 LAST HDL_TAP TRUE
J 0
(-5950 4550);
DISPLAY 0.872340 (-5950 4550);
DISPLAY INVISIBLE (-5950 4550);
FORCEPROP 1 LAST PATH I252
J 0
(-6277 4675);
DISPLAY 0.872340 (-6277 4675);
PAINT GREEN (-6277 4675);
DISPLAY INVISIBLE (-6277 4675);
FORCEADD TAP..1
(-6275 4625);
FORCEPROP 3 LASTPIN (-6325 4625) SIG_NAME M_E_CPU0_SA_DQ<12>
J 0
(-6315 4635);
DISPLAY 0.659574 (-6315 4635);
PAINT MONO (-6315 4635);
DISPLAY INVISIBLE (-6315 4635);
FORCEPROP 1 LASTPIN (-6325 4625) BN 12
J 0
(-6337 4633);
DISPLAY 0.489362 (-6337 4633);
PAINT GREEN (-6337 4633);
FORCEPROP 2 LAST CDS_LIB mstr_standard
J 0
(-6275 4625);
DISPLAY 0.723404 (-6275 4625);
PAINT MONO (-6275 4625);
DISPLAY INVISIBLE (-6275 4625);
FORCEPROP 1 LAST BODY_TYPE PLUMBING
J 0
(-6275 4675);
DISPLAY 0.872340 (-6275 4675);
PAINT GREEN (-6275 4675);
DISPLAY INVISIBLE (-6275 4675);
FORCEPROP 1 LAST HDL_TAP TRUE
J 0
(-5950 4500);
DISPLAY 0.872340 (-5950 4500);
DISPLAY INVISIBLE (-5950 4500);
FORCEPROP 1 LAST PATH I253
J 0
(-6277 4625);
DISPLAY 0.872340 (-6277 4625);
PAINT GREEN (-6277 4625);
DISPLAY INVISIBLE (-6277 4625);
FORCEADD TAP..1
(-6275 4575);
FORCEPROP 3 LASTPIN (-6325 4575) SIG_NAME M_E_CPU0_SA_DQ<11>
J 0
(-6315 4585);
DISPLAY 0.659574 (-6315 4585);
PAINT MONO (-6315 4585);
DISPLAY INVISIBLE (-6315 4585);
FORCEPROP 1 LASTPIN (-6325 4575) BN 11
J 0
(-6337 4583);
DISPLAY 0.489362 (-6337 4583);
PAINT GREEN (-6337 4583);
FORCEPROP 2 LAST CDS_LIB mstr_standard
J 0
(-6275 4575);
DISPLAY 0.723404 (-6275 4575);
PAINT MONO (-6275 4575);
DISPLAY INVISIBLE (-6275 4575);
FORCEPROP 1 LAST BODY_TYPE PLUMBING
J 0
(-6275 4625);
DISPLAY 0.872340 (-6275 4625);
PAINT GREEN (-6275 4625);
DISPLAY INVISIBLE (-6275 4625);
FORCEPROP 1 LAST HDL_TAP TRUE
J 0
(-5950 4450);
DISPLAY 0.872340 (-5950 4450);
DISPLAY INVISIBLE (-5950 4450);
FORCEPROP 1 LAST PATH I254
J 0
(-6277 4575);
DISPLAY 0.872340 (-6277 4575);
PAINT GREEN (-6277 4575);
DISPLAY INVISIBLE (-6277 4575);
FORCEADD TAP..1
(-6275 4875);
FORCEPROP 3 LASTPIN (-6325 4875) SIG_NAME M_E_CPU0_SA_DQ<17>
J 0
(-6315 4885);
DISPLAY 0.659574 (-6315 4885);
PAINT MONO (-6315 4885);
DISPLAY INVISIBLE (-6315 4885);
FORCEPROP 1 LASTPIN (-6325 4875) BN 17
J 0
(-6337 4883);
DISPLAY 0.489362 (-6337 4883);
PAINT GREEN (-6337 4883);
FORCEPROP 2 LAST CDS_LIB mstr_standard
J 0
(-6275 4875);
DISPLAY 0.723404 (-6275 4875);
PAINT MONO (-6275 4875);
DISPLAY INVISIBLE (-6275 4875);
FORCEPROP 1 LAST BODY_TYPE PLUMBING
J 0
(-6275 4925);
DISPLAY 0.872340 (-6275 4925);
PAINT GREEN (-6275 4925);
DISPLAY INVISIBLE (-6275 4925);
FORCEPROP 1 LAST HDL_TAP TRUE
J 0
(-5950 4750);
DISPLAY 0.872340 (-5950 4750);
DISPLAY INVISIBLE (-5950 4750);
FORCEPROP 1 LAST PATH I255
J 0
(-6277 4875);
DISPLAY 0.872340 (-6277 4875);
PAINT GREEN (-6277 4875);
DISPLAY INVISIBLE (-6277 4875);
FORCEADD TAP..1
(-6275 4925);
FORCEPROP 3 LASTPIN (-6325 4925) SIG_NAME M_E_CPU0_SA_DQ<18>
J 0
(-6315 4935);
DISPLAY 0.659574 (-6315 4935);
PAINT MONO (-6315 4935);
DISPLAY INVISIBLE (-6315 4935);
FORCEPROP 1 LASTPIN (-6325 4925) BN 18
J 0
(-6337 4933);
DISPLAY 0.489362 (-6337 4933);
PAINT GREEN (-6337 4933);
FORCEPROP 2 LAST CDS_LIB mstr_standard
J 0
(-6275 4925);
DISPLAY 0.723404 (-6275 4925);
PAINT MONO (-6275 4925);
DISPLAY INVISIBLE (-6275 4925);
FORCEPROP 1 LAST BODY_TYPE PLUMBING
J 0
(-6275 4975);
DISPLAY 0.872340 (-6275 4975);
PAINT GREEN (-6275 4975);
DISPLAY INVISIBLE (-6275 4975);
FORCEPROP 1 LAST HDL_TAP TRUE
J 0
(-5950 4800);
DISPLAY 0.872340 (-5950 4800);
DISPLAY INVISIBLE (-5950 4800);
FORCEPROP 1 LAST PATH I256
J 0
(-6277 4925);
DISPLAY 0.872340 (-6277 4925);
PAINT GREEN (-6277 4925);
DISPLAY INVISIBLE (-6277 4925);
FORCEADD TAP..1
(-6275 4825);
FORCEPROP 3 LASTPIN (-6325 4825) SIG_NAME M_E_CPU0_SA_DQ<16>
J 0
(-6315 4835);
DISPLAY 0.659574 (-6315 4835);
PAINT MONO (-6315 4835);
DISPLAY INVISIBLE (-6315 4835);
FORCEPROP 1 LASTPIN (-6325 4825) BN 16
J 0
(-6337 4833);
DISPLAY 0.489362 (-6337 4833);
PAINT GREEN (-6337 4833);
FORCEPROP 2 LAST CDS_LIB mstr_standard
J 0
(-6275 4825);
DISPLAY 0.723404 (-6275 4825);
PAINT MONO (-6275 4825);
DISPLAY INVISIBLE (-6275 4825);
FORCEPROP 1 LAST BODY_TYPE PLUMBING
J 0
(-6275 4875);
DISPLAY 0.872340 (-6275 4875);
PAINT GREEN (-6275 4875);
DISPLAY INVISIBLE (-6275 4875);
FORCEPROP 1 LAST HDL_TAP TRUE
J 0
(-5950 4700);
DISPLAY 0.872340 (-5950 4700);
DISPLAY INVISIBLE (-5950 4700);
FORCEPROP 1 LAST PATH I257
J 0
(-6277 4825);
DISPLAY 0.872340 (-6277 4825);
PAINT GREEN (-6277 4825);
DISPLAY INVISIBLE (-6277 4825);
FORCEADD TAP..1
(-6275 5025);
FORCEPROP 3 LASTPIN (-6325 5025) SIG_NAME M_E_CPU0_SA_DQ<20>
J 0
(-6315 5035);
DISPLAY 0.659574 (-6315 5035);
PAINT MONO (-6315 5035);
DISPLAY INVISIBLE (-6315 5035);
FORCEPROP 1 LASTPIN (-6325 5025) BN 20
J 0
(-6337 5033);
DISPLAY 0.489362 (-6337 5033);
PAINT GREEN (-6337 5033);
FORCEPROP 2 LAST CDS_LIB mstr_standard
J 0
(-6275 5025);
DISPLAY 0.723404 (-6275 5025);
PAINT MONO (-6275 5025);
DISPLAY INVISIBLE (-6275 5025);
FORCEPROP 1 LAST BODY_TYPE PLUMBING
J 0
(-6275 5075);
DISPLAY 0.872340 (-6275 5075);
PAINT GREEN (-6275 5075);
DISPLAY INVISIBLE (-6275 5075);
FORCEPROP 1 LAST HDL_TAP TRUE
J 0
(-5950 4900);
DISPLAY 0.872340 (-5950 4900);
DISPLAY INVISIBLE (-5950 4900);
FORCEPROP 1 LAST PATH I258
J 0
(-6277 5025);
DISPLAY 0.872340 (-6277 5025);
PAINT GREEN (-6277 5025);
DISPLAY INVISIBLE (-6277 5025);
FORCEADD TAP..1
(-6275 4975);
FORCEPROP 3 LASTPIN (-6325 4975) SIG_NAME M_E_CPU0_SA_DQ<19>
J 0
(-6315 4985);
DISPLAY 0.659574 (-6315 4985);
PAINT MONO (-6315 4985);
DISPLAY INVISIBLE (-6315 4985);
FORCEPROP 1 LASTPIN (-6325 4975) BN 19
J 0
(-6337 4983);
DISPLAY 0.489362 (-6337 4983);
PAINT GREEN (-6337 4983);
FORCEPROP 2 LAST CDS_LIB mstr_standard
J 0
(-6275 4975);
DISPLAY 0.723404 (-6275 4975);
PAINT MONO (-6275 4975);
DISPLAY INVISIBLE (-6275 4975);
FORCEPROP 1 LAST BODY_TYPE PLUMBING
J 0
(-6275 5025);
DISPLAY 0.872340 (-6275 5025);
PAINT GREEN (-6275 5025);
DISPLAY INVISIBLE (-6275 5025);
FORCEPROP 1 LAST HDL_TAP TRUE
J 0
(-5950 4850);
DISPLAY 0.872340 (-5950 4850);
DISPLAY INVISIBLE (-5950 4850);
FORCEPROP 1 LAST PATH I259
J 0
(-6277 4975);
DISPLAY 0.872340 (-6277 4975);
PAINT GREEN (-6277 4975);
DISPLAY INVISIBLE (-6277 4975);
FORCEADD OFFPAGE..3
(-5625 4000);
FORCEPROP 2 LAST $XR0 14 
J 0
(-5411 4000);
DISPLAY 0.638298 (-5411 4000);
PAINT MONO (-5411 4000);
FORCEPROP 2 LAST CDS_LIB mstr_standard
J 0
(-5625 4000);
DISPLAY 0.723404 (-5625 4000);
PAINT MONO (-5625 4000);
DISPLAY INVISIBLE (-5625 4000);
FORCEPROP 1 LAST OFFPAGE TRUE
J 0
(-5300 3875);
DISPLAY 0.872340 (-5300 3875);
PAINT GREEN (-5300 3875);
DISPLAY INVISIBLE (-5300 3875);
FORCEPROP 1 LAST COMMENT_BODY TRUE
J 0
(-5675 3900);
DISPLAY 0.872340 (-5675 3900);
PAINT GREEN (-5675 3900);
DISPLAY INVISIBLE (-5675 3900);
FORCEPROP 2 LAST PATH I260
J 0
(-5300 4050);
DISPLAY 0.808511 (-5300 4050);
DISPLAY INVISIBLE (-5300 4050);
FORCEADD OFFPAGE..1
(-8575 5225);
FORCEPROP 2 LAST $XR0 14 
J 0
(-8826 5225);
DISPLAY 0.638298 (-8826 5225);
PAINT MONO (-8826 5225);
FORCEPROP 2 LAST CDS_LIB mstr_standard
J 0
(-8575 5225);
DISPLAY 0.723404 (-8575 5225);
PAINT MONO (-8575 5225);
DISPLAY INVISIBLE (-8575 5225);
FORCEPROP 1 LAST OFFPAGE TRUE
J 0
(-8250 5100);
DISPLAY 0.872340 (-8250 5100);
PAINT GREEN (-8250 5100);
DISPLAY INVISIBLE (-8250 5100);
FORCEPROP 1 LAST COMMENT_BODY TRUE
J 0
(-8450 5125);
DISPLAY 0.872340 (-8450 5125);
PAINT GREEN (-8450 5125);
DISPLAY INVISIBLE (-8450 5125);
FORCEPROP 2 LAST PATH I261
J 0
(-8525 5300);
DISPLAY 0.808511 (-8525 5300);
DISPLAY INVISIBLE (-8525 5300);
FORCEADD OFFPAGE..1
(-8575 5625);
FORCEPROP 2 LAST $XR0 14 
J 0
(-8826 5625);
DISPLAY 0.638298 (-8826 5625);
PAINT MONO (-8826 5625);
FORCEPROP 2 LAST CDS_LIB mstr_standard
J 0
(-8575 5625);
DISPLAY 0.723404 (-8575 5625);
PAINT MONO (-8575 5625);
DISPLAY INVISIBLE (-8575 5625);
FORCEPROP 1 LAST OFFPAGE TRUE
J 0
(-8250 5500);
DISPLAY 0.872340 (-8250 5500);
PAINT GREEN (-8250 5500);
DISPLAY INVISIBLE (-8250 5500);
FORCEPROP 1 LAST COMMENT_BODY TRUE
J 0
(-8450 5525);
DISPLAY 0.872340 (-8450 5525);
PAINT GREEN (-8450 5525);
DISPLAY INVISIBLE (-8450 5525);
FORCEPROP 2 LAST PATH I262
J 0
(-8525 5700);
DISPLAY 0.808511 (-8525 5700);
DISPLAY INVISIBLE (-8525 5700);
FORCEADD TAP..1
R 2
(-7975 5175);
FORCEPROP 3 LASTPIN (-7925 5175) SIG_NAME M_E_CPU0_SB_CA<6>
J 0
(-7915 5185);
DISPLAY 0.659574 (-7915 5185);
PAINT MONO (-7915 5185);
DISPLAY INVISIBLE (-7915 5185);
FORCEPROP 1 LASTPIN (-7925 5175) BN 6
J 2
(-7913 5183);
DISPLAY 0.489362 (-7913 5183);
PAINT GREEN (-7913 5183);
FORCEPROP 2 LAST CDS_LIB mstr_standard
J 0
(-7975 5175);
DISPLAY 0.723404 (-7975 5175);
PAINT MONO (-7975 5175);
DISPLAY INVISIBLE (-7975 5175);
FORCEPROP 1 LAST BODY_TYPE PLUMBING
J 2
(-7975 5225);
DISPLAY 0.872340 (-7975 5225);
PAINT GREEN (-7975 5225);
DISPLAY INVISIBLE (-7975 5225);
FORCEPROP 1 LAST HDL_TAP TRUE
J 2
(-8300 5050);
DISPLAY 0.872340 (-8300 5050);
DISPLAY INVISIBLE (-8300 5050);
FORCEPROP 1 LAST PATH I263
J 2
(-7973 5175);
DISPLAY 0.872340 (-7973 5175);
PAINT GREEN (-7973 5175);
DISPLAY INVISIBLE (-7973 5175);
FORCEADD TAP..1
R 2
(-7975 5075);
FORCEPROP 3 LASTPIN (-7925 5075) SIG_NAME M_E_CPU0_SB_CA<4>
J 0
(-7915 5085);
DISPLAY 0.659574 (-7915 5085);
PAINT MONO (-7915 5085);
DISPLAY INVISIBLE (-7915 5085);
FORCEPROP 1 LASTPIN (-7925 5075) BN 4
J 2
(-7913 5083);
DISPLAY 0.489362 (-7913 5083);
PAINT GREEN (-7913 5083);
FORCEPROP 2 LAST CDS_LIB mstr_standard
J 0
(-7975 5075);
DISPLAY 0.723404 (-7975 5075);
PAINT MONO (-7975 5075);
DISPLAY INVISIBLE (-7975 5075);
FORCEPROP 1 LAST BODY_TYPE PLUMBING
J 2
(-7975 5125);
DISPLAY 0.872340 (-7975 5125);
PAINT GREEN (-7975 5125);
DISPLAY INVISIBLE (-7975 5125);
FORCEPROP 1 LAST HDL_TAP TRUE
J 2
(-8300 4950);
DISPLAY 0.872340 (-8300 4950);
DISPLAY INVISIBLE (-8300 4950);
FORCEPROP 1 LAST PATH I264
J 2
(-7973 5075);
DISPLAY 0.872340 (-7973 5075);
PAINT GREEN (-7973 5075);
DISPLAY INVISIBLE (-7973 5075);
FORCEADD TAP..1
R 2
(-7975 5125);
FORCEPROP 3 LASTPIN (-7925 5125) SIG_NAME M_E_CPU0_SB_CA<5>
J 0
(-7915 5135);
DISPLAY 0.659574 (-7915 5135);
PAINT MONO (-7915 5135);
DISPLAY INVISIBLE (-7915 5135);
FORCEPROP 1 LASTPIN (-7925 5125) BN 5
J 2
(-7913 5133);
DISPLAY 0.489362 (-7913 5133);
PAINT GREEN (-7913 5133);
FORCEPROP 2 LAST CDS_LIB mstr_standard
J 0
(-7975 5125);
DISPLAY 0.723404 (-7975 5125);
PAINT MONO (-7975 5125);
DISPLAY INVISIBLE (-7975 5125);
FORCEPROP 1 LAST BODY_TYPE PLUMBING
J 2
(-7975 5175);
DISPLAY 0.872340 (-7975 5175);
PAINT GREEN (-7975 5175);
DISPLAY INVISIBLE (-7975 5175);
FORCEPROP 1 LAST HDL_TAP TRUE
J 2
(-8300 5000);
DISPLAY 0.872340 (-8300 5000);
DISPLAY INVISIBLE (-8300 5000);
FORCEPROP 1 LAST PATH I265
J 2
(-7973 5125);
DISPLAY 0.872340 (-7973 5125);
PAINT GREEN (-7973 5125);
DISPLAY INVISIBLE (-7973 5125);
FORCEADD TAP..1
R 2
(-7975 5275);
FORCEPROP 3 LASTPIN (-7925 5275) SIG_NAME M_E_CPU0_SA_CA<0>
J 0
(-7915 5285);
DISPLAY 0.659574 (-7915 5285);
PAINT MONO (-7915 5285);
DISPLAY INVISIBLE (-7915 5285);
FORCEPROP 1 LASTPIN (-7925 5275) BN 0
J 2
(-7913 5283);
DISPLAY 0.489362 (-7913 5283);
PAINT GREEN (-7913 5283);
FORCEPROP 2 LAST CDS_LIB mstr_standard
J 0
(-7975 5275);
DISPLAY 0.723404 (-7975 5275);
PAINT MONO (-7975 5275);
DISPLAY INVISIBLE (-7975 5275);
FORCEPROP 1 LAST BODY_TYPE PLUMBING
J 2
(-7975 5325);
DISPLAY 0.872340 (-7975 5325);
PAINT GREEN (-7975 5325);
DISPLAY INVISIBLE (-7975 5325);
FORCEPROP 1 LAST HDL_TAP TRUE
J 2
(-8300 5150);
DISPLAY 0.872340 (-8300 5150);
DISPLAY INVISIBLE (-8300 5150);
FORCEPROP 1 LAST PATH I266
J 2
(-7973 5275);
DISPLAY 0.872340 (-7973 5275);
PAINT GREEN (-7973 5275);
DISPLAY INVISIBLE (-7973 5275);
FORCEADD TAP..1
R 2
(-7975 5325);
FORCEPROP 3 LASTPIN (-7925 5325) SIG_NAME M_E_CPU0_SA_CA<1>
J 0
(-7915 5335);
DISPLAY 0.659574 (-7915 5335);
PAINT MONO (-7915 5335);
DISPLAY INVISIBLE (-7915 5335);
FORCEPROP 1 LASTPIN (-7925 5325) BN 1
J 2
(-7913 5333);
DISPLAY 0.489362 (-7913 5333);
PAINT GREEN (-7913 5333);
FORCEPROP 2 LAST CDS_LIB mstr_standard
J 0
(-7975 5325);
DISPLAY 0.723404 (-7975 5325);
PAINT MONO (-7975 5325);
DISPLAY INVISIBLE (-7975 5325);
FORCEPROP 1 LAST BODY_TYPE PLUMBING
J 2
(-7975 5375);
DISPLAY 0.872340 (-7975 5375);
PAINT GREEN (-7975 5375);
DISPLAY INVISIBLE (-7975 5375);
FORCEPROP 1 LAST HDL_TAP TRUE
J 2
(-8300 5200);
DISPLAY 0.872340 (-8300 5200);
DISPLAY INVISIBLE (-8300 5200);
FORCEPROP 1 LAST PATH I267
J 2
(-7973 5325);
DISPLAY 0.872340 (-7973 5325);
PAINT GREEN (-7973 5325);
DISPLAY INVISIBLE (-7973 5325);
FORCEADD TAP..1
R 2
(-7975 5375);
FORCEPROP 3 LASTPIN (-7925 5375) SIG_NAME M_E_CPU0_SA_CA<2>
J 0
(-7915 5385);
DISPLAY 0.659574 (-7915 5385);
PAINT MONO (-7915 5385);
DISPLAY INVISIBLE (-7915 5385);
FORCEPROP 1 LASTPIN (-7925 5375) BN 2
J 2
(-7913 5383);
DISPLAY 0.489362 (-7913 5383);
PAINT GREEN (-7913 5383);
FORCEPROP 2 LAST CDS_LIB mstr_standard
J 0
(-7975 5375);
DISPLAY 0.723404 (-7975 5375);
PAINT MONO (-7975 5375);
DISPLAY INVISIBLE (-7975 5375);
FORCEPROP 1 LAST BODY_TYPE PLUMBING
J 2
(-7975 5425);
DISPLAY 0.872340 (-7975 5425);
PAINT GREEN (-7975 5425);
DISPLAY INVISIBLE (-7975 5425);
FORCEPROP 1 LAST HDL_TAP TRUE
J 2
(-8300 5250);
DISPLAY 0.872340 (-8300 5250);
DISPLAY INVISIBLE (-8300 5250);
FORCEPROP 1 LAST PATH I268
J 2
(-7973 5375);
DISPLAY 0.872340 (-7973 5375);
PAINT GREEN (-7973 5375);
DISPLAY INVISIBLE (-7973 5375);
FORCEADD TAP..1
R 2
(-7975 5425);
FORCEPROP 3 LASTPIN (-7925 5425) SIG_NAME M_E_CPU0_SA_CA<3>
J 0
(-7915 5435);
DISPLAY 0.659574 (-7915 5435);
PAINT MONO (-7915 5435);
DISPLAY INVISIBLE (-7915 5435);
FORCEPROP 1 LASTPIN (-7925 5425) BN 3
J 2
(-7913 5433);
DISPLAY 0.489362 (-7913 5433);
PAINT GREEN (-7913 5433);
FORCEPROP 2 LAST CDS_LIB mstr_standard
J 0
(-7975 5425);
DISPLAY 0.723404 (-7975 5425);
PAINT MONO (-7975 5425);
DISPLAY INVISIBLE (-7975 5425);
FORCEPROP 1 LAST BODY_TYPE PLUMBING
J 2
(-7975 5475);
DISPLAY 0.872340 (-7975 5475);
PAINT GREEN (-7975 5475);
DISPLAY INVISIBLE (-7975 5475);
FORCEPROP 1 LAST HDL_TAP TRUE
J 2
(-8300 5300);
DISPLAY 0.872340 (-8300 5300);
DISPLAY INVISIBLE (-8300 5300);
FORCEPROP 1 LAST PATH I269
J 2
(-7973 5425);
DISPLAY 0.872340 (-7973 5425);
PAINT GREEN (-7973 5425);
DISPLAY INVISIBLE (-7973 5425);
FORCEADD TAP..1
R 2
(-7975 5525);
FORCEPROP 3 LASTPIN (-7925 5525) SIG_NAME M_E_CPU0_SA_CA<5>
J 0
(-7915 5535);
DISPLAY 0.659574 (-7915 5535);
PAINT MONO (-7915 5535);
DISPLAY INVISIBLE (-7915 5535);
FORCEPROP 1 LASTPIN (-7925 5525) BN 5
J 2
(-7913 5533);
DISPLAY 0.489362 (-7913 5533);
PAINT GREEN (-7913 5533);
FORCEPROP 2 LAST CDS_LIB mstr_standard
J 0
(-7975 5525);
DISPLAY 0.723404 (-7975 5525);
PAINT MONO (-7975 5525);
DISPLAY INVISIBLE (-7975 5525);
FORCEPROP 1 LAST BODY_TYPE PLUMBING
J 2
(-7975 5575);
DISPLAY 0.872340 (-7975 5575);
PAINT GREEN (-7975 5575);
DISPLAY INVISIBLE (-7975 5575);
FORCEPROP 1 LAST HDL_TAP TRUE
J 2
(-8300 5400);
DISPLAY 0.872340 (-8300 5400);
DISPLAY INVISIBLE (-8300 5400);
FORCEPROP 1 LAST PATH I270
J 2
(-7973 5525);
DISPLAY 0.872340 (-7973 5525);
PAINT GREEN (-7973 5525);
DISPLAY INVISIBLE (-7973 5525);
FORCEADD TAP..1
R 2
(-7975 5475);
FORCEPROP 3 LASTPIN (-7925 5475) SIG_NAME M_E_CPU0_SA_CA<4>
J 0
(-7915 5485);
DISPLAY 0.659574 (-7915 5485);
PAINT MONO (-7915 5485);
DISPLAY INVISIBLE (-7915 5485);
FORCEPROP 1 LASTPIN (-7925 5475) BN 4
J 2
(-7913 5483);
DISPLAY 0.489362 (-7913 5483);
PAINT GREEN (-7913 5483);
FORCEPROP 2 LAST CDS_LIB mstr_standard
J 0
(-7975 5475);
DISPLAY 0.723404 (-7975 5475);
PAINT MONO (-7975 5475);
DISPLAY INVISIBLE (-7975 5475);
FORCEPROP 1 LAST BODY_TYPE PLUMBING
J 2
(-7975 5525);
DISPLAY 0.872340 (-7975 5525);
PAINT GREEN (-7975 5525);
DISPLAY INVISIBLE (-7975 5525);
FORCEPROP 1 LAST HDL_TAP TRUE
J 2
(-8300 5350);
DISPLAY 0.872340 (-8300 5350);
DISPLAY INVISIBLE (-8300 5350);
FORCEPROP 1 LAST PATH I271
J 2
(-7973 5475);
DISPLAY 0.872340 (-7973 5475);
PAINT GREEN (-7973 5475);
DISPLAY INVISIBLE (-7973 5475);
FORCEADD TAP..1
R 2
(-7975 5575);
FORCEPROP 3 LASTPIN (-7925 5575) SIG_NAME M_E_CPU0_SA_CA<6>
J 0
(-7915 5585);
DISPLAY 0.659574 (-7915 5585);
PAINT MONO (-7915 5585);
DISPLAY INVISIBLE (-7915 5585);
FORCEPROP 1 LASTPIN (-7925 5575) BN 6
J 2
(-7913 5583);
DISPLAY 0.489362 (-7913 5583);
PAINT GREEN (-7913 5583);
FORCEPROP 2 LAST CDS_LIB mstr_standard
J 0
(-7975 5575);
DISPLAY 0.723404 (-7975 5575);
PAINT MONO (-7975 5575);
DISPLAY INVISIBLE (-7975 5575);
FORCEPROP 1 LAST BODY_TYPE PLUMBING
J 2
(-7975 5625);
DISPLAY 0.872340 (-7975 5625);
PAINT GREEN (-7975 5625);
DISPLAY INVISIBLE (-7975 5625);
FORCEPROP 1 LAST HDL_TAP TRUE
J 2
(-8300 5450);
DISPLAY 0.872340 (-8300 5450);
DISPLAY INVISIBLE (-8300 5450);
FORCEPROP 1 LAST PATH I272
J 2
(-7973 5575);
DISPLAY 0.872340 (-7973 5575);
PAINT GREEN (-7973 5575);
DISPLAY INVISIBLE (-7973 5575);
FORCEADD TAP..1
(-6275 5175);
FORCEPROP 3 LASTPIN (-6325 5175) SIG_NAME M_E_CPU0_SA_DQ<23>
J 0
(-6315 5185);
DISPLAY 0.659574 (-6315 5185);
PAINT MONO (-6315 5185);
DISPLAY INVISIBLE (-6315 5185);
FORCEPROP 1 LASTPIN (-6325 5175) BN 23
J 0
(-6337 5183);
DISPLAY 0.489362 (-6337 5183);
PAINT GREEN (-6337 5183);
FORCEPROP 2 LAST CDS_LIB mstr_standard
J 0
(-6275 5175);
DISPLAY 0.723404 (-6275 5175);
PAINT MONO (-6275 5175);
DISPLAY INVISIBLE (-6275 5175);
FORCEPROP 1 LAST BODY_TYPE PLUMBING
J 0
(-6275 5225);
DISPLAY 0.872340 (-6275 5225);
PAINT GREEN (-6275 5225);
DISPLAY INVISIBLE (-6275 5225);
FORCEPROP 1 LAST HDL_TAP TRUE
J 0
(-5950 5050);
DISPLAY 0.872340 (-5950 5050);
DISPLAY INVISIBLE (-5950 5050);
FORCEPROP 1 LAST PATH I273
J 0
(-6277 5175);
DISPLAY 0.872340 (-6277 5175);
PAINT GREEN (-6277 5175);
DISPLAY INVISIBLE (-6277 5175);
FORCEADD TAP..1
(-6275 5075);
FORCEPROP 3 LASTPIN (-6325 5075) SIG_NAME M_E_CPU0_SA_DQ<21>
J 0
(-6315 5085);
DISPLAY 0.659574 (-6315 5085);
PAINT MONO (-6315 5085);
DISPLAY INVISIBLE (-6315 5085);
FORCEPROP 1 LASTPIN (-6325 5075) BN 21
J 0
(-6337 5083);
DISPLAY 0.489362 (-6337 5083);
PAINT GREEN (-6337 5083);
FORCEPROP 2 LAST CDS_LIB mstr_standard
J 0
(-6275 5075);
DISPLAY 0.723404 (-6275 5075);
PAINT MONO (-6275 5075);
DISPLAY INVISIBLE (-6275 5075);
FORCEPROP 1 LAST BODY_TYPE PLUMBING
J 0
(-6275 5125);
DISPLAY 0.872340 (-6275 5125);
PAINT GREEN (-6275 5125);
DISPLAY INVISIBLE (-6275 5125);
FORCEPROP 1 LAST HDL_TAP TRUE
J 0
(-5950 4950);
DISPLAY 0.872340 (-5950 4950);
DISPLAY INVISIBLE (-5950 4950);
FORCEPROP 1 LAST PATH I274
J 0
(-6277 5075);
DISPLAY 0.872340 (-6277 5075);
PAINT GREEN (-6277 5075);
DISPLAY INVISIBLE (-6277 5075);
FORCEADD TAP..1
(-6275 5125);
FORCEPROP 3 LASTPIN (-6325 5125) SIG_NAME M_E_CPU0_SA_DQ<22>
J 0
(-6315 5135);
DISPLAY 0.659574 (-6315 5135);
PAINT MONO (-6315 5135);
DISPLAY INVISIBLE (-6315 5135);
FORCEPROP 1 LASTPIN (-6325 5125) BN 22
J 0
(-6337 5133);
DISPLAY 0.489362 (-6337 5133);
PAINT GREEN (-6337 5133);
FORCEPROP 2 LAST CDS_LIB mstr_standard
J 0
(-6275 5125);
DISPLAY 0.723404 (-6275 5125);
PAINT MONO (-6275 5125);
DISPLAY INVISIBLE (-6275 5125);
FORCEPROP 1 LAST BODY_TYPE PLUMBING
J 0
(-6275 5175);
DISPLAY 0.872340 (-6275 5175);
PAINT GREEN (-6275 5175);
DISPLAY INVISIBLE (-6275 5175);
FORCEPROP 1 LAST HDL_TAP TRUE
J 0
(-5950 5000);
DISPLAY 0.872340 (-5950 5000);
DISPLAY INVISIBLE (-5950 5000);
FORCEPROP 1 LAST PATH I275
J 0
(-6277 5125);
DISPLAY 0.872340 (-6277 5125);
PAINT GREEN (-6277 5125);
DISPLAY INVISIBLE (-6277 5125);
FORCEADD TAP..1
(-6275 5225);
FORCEPROP 3 LASTPIN (-6325 5225) SIG_NAME M_E_CPU0_SA_DQ<24>
J 0
(-6315 5235);
DISPLAY 0.659574 (-6315 5235);
PAINT MONO (-6315 5235);
DISPLAY INVISIBLE (-6315 5235);
FORCEPROP 1 LASTPIN (-6325 5225) BN 24
J 0
(-6337 5233);
DISPLAY 0.489362 (-6337 5233);
PAINT GREEN (-6337 5233);
FORCEPROP 2 LAST CDS_LIB mstr_standard
J 0
(-6275 5225);
DISPLAY 0.723404 (-6275 5225);
PAINT MONO (-6275 5225);
DISPLAY INVISIBLE (-6275 5225);
FORCEPROP 1 LAST BODY_TYPE PLUMBING
J 0
(-6275 5275);
DISPLAY 0.872340 (-6275 5275);
PAINT GREEN (-6275 5275);
DISPLAY INVISIBLE (-6275 5275);
FORCEPROP 1 LAST HDL_TAP TRUE
J 0
(-5950 5100);
DISPLAY 0.872340 (-5950 5100);
DISPLAY INVISIBLE (-5950 5100);
FORCEPROP 1 LAST PATH I276
J 0
(-6277 5225);
DISPLAY 0.872340 (-6277 5225);
PAINT GREEN (-6277 5225);
DISPLAY INVISIBLE (-6277 5225);
FORCEADD TAP..1
(-6275 5275);
FORCEPROP 3 LASTPIN (-6325 5275) SIG_NAME M_E_CPU0_SA_DQ<25>
J 0
(-6315 5285);
DISPLAY 0.659574 (-6315 5285);
PAINT MONO (-6315 5285);
DISPLAY INVISIBLE (-6315 5285);
FORCEPROP 1 LASTPIN (-6325 5275) BN 25
J 0
(-6337 5283);
DISPLAY 0.489362 (-6337 5283);
PAINT GREEN (-6337 5283);
FORCEPROP 2 LAST CDS_LIB mstr_standard
J 0
(-6275 5275);
DISPLAY 0.723404 (-6275 5275);
PAINT MONO (-6275 5275);
DISPLAY INVISIBLE (-6275 5275);
FORCEPROP 1 LAST BODY_TYPE PLUMBING
J 0
(-6275 5325);
DISPLAY 0.872340 (-6275 5325);
PAINT GREEN (-6275 5325);
DISPLAY INVISIBLE (-6275 5325);
FORCEPROP 1 LAST HDL_TAP TRUE
J 0
(-5950 5150);
DISPLAY 0.872340 (-5950 5150);
DISPLAY INVISIBLE (-5950 5150);
FORCEPROP 1 LAST PATH I277
J 0
(-6277 5275);
DISPLAY 0.872340 (-6277 5275);
PAINT GREEN (-6277 5275);
DISPLAY INVISIBLE (-6277 5275);
FORCEADD TAP..1
(-6275 5325);
FORCEPROP 3 LASTPIN (-6325 5325) SIG_NAME M_E_CPU0_SA_DQ<26>
J 0
(-6315 5335);
DISPLAY 0.659574 (-6315 5335);
PAINT MONO (-6315 5335);
DISPLAY INVISIBLE (-6315 5335);
FORCEPROP 1 LASTPIN (-6325 5325) BN 26
J 0
(-6337 5333);
DISPLAY 0.489362 (-6337 5333);
PAINT GREEN (-6337 5333);
FORCEPROP 2 LAST CDS_LIB mstr_standard
J 0
(-6275 5325);
DISPLAY 0.723404 (-6275 5325);
PAINT MONO (-6275 5325);
DISPLAY INVISIBLE (-6275 5325);
FORCEPROP 1 LAST BODY_TYPE PLUMBING
J 0
(-6275 5375);
DISPLAY 0.872340 (-6275 5375);
PAINT GREEN (-6275 5375);
DISPLAY INVISIBLE (-6275 5375);
FORCEPROP 1 LAST HDL_TAP TRUE
J 0
(-5950 5200);
DISPLAY 0.872340 (-5950 5200);
DISPLAY INVISIBLE (-5950 5200);
FORCEPROP 1 LAST PATH I278
J 0
(-6277 5325);
DISPLAY 0.872340 (-6277 5325);
PAINT GREEN (-6277 5325);
DISPLAY INVISIBLE (-6277 5325);
FORCEADD TAP..1
(-6275 5575);
FORCEPROP 3 LASTPIN (-6325 5575) SIG_NAME M_E_CPU0_SA_DQ<31>
J 0
(-6315 5585);
DISPLAY 0.659574 (-6315 5585);
PAINT MONO (-6315 5585);
DISPLAY INVISIBLE (-6315 5585);
FORCEPROP 1 LASTPIN (-6325 5575) BN 31
J 0
(-6337 5583);
DISPLAY 0.489362 (-6337 5583);
PAINT GREEN (-6337 5583);
FORCEPROP 2 LAST CDS_LIB mstr_standard
J 0
(-6275 5575);
DISPLAY 0.723404 (-6275 5575);
PAINT MONO (-6275 5575);
DISPLAY INVISIBLE (-6275 5575);
FORCEPROP 1 LAST BODY_TYPE PLUMBING
J 0
(-6275 5625);
DISPLAY 0.872340 (-6275 5625);
PAINT GREEN (-6275 5625);
DISPLAY INVISIBLE (-6275 5625);
FORCEPROP 1 LAST HDL_TAP TRUE
J 0
(-5950 5450);
DISPLAY 0.872340 (-5950 5450);
DISPLAY INVISIBLE (-5950 5450);
FORCEPROP 1 LAST PATH I279
J 0
(-6277 5575);
DISPLAY 0.872340 (-6277 5575);
PAINT GREEN (-6277 5575);
DISPLAY INVISIBLE (-6277 5575);
FORCEADD TAP..1
(-6275 5375);
FORCEPROP 3 LASTPIN (-6325 5375) SIG_NAME M_E_CPU0_SA_DQ<27>
J 0
(-6315 5385);
DISPLAY 0.659574 (-6315 5385);
PAINT MONO (-6315 5385);
DISPLAY INVISIBLE (-6315 5385);
FORCEPROP 1 LASTPIN (-6325 5375) BN 27
J 0
(-6337 5383);
DISPLAY 0.489362 (-6337 5383);
PAINT GREEN (-6337 5383);
FORCEPROP 2 LAST CDS_LIB mstr_standard
J 0
(-6275 5375);
DISPLAY 0.723404 (-6275 5375);
PAINT MONO (-6275 5375);
DISPLAY INVISIBLE (-6275 5375);
FORCEPROP 1 LAST BODY_TYPE PLUMBING
J 0
(-6275 5425);
DISPLAY 0.872340 (-6275 5425);
PAINT GREEN (-6275 5425);
DISPLAY INVISIBLE (-6275 5425);
FORCEPROP 1 LAST HDL_TAP TRUE
J 0
(-5950 5250);
DISPLAY 0.872340 (-5950 5250);
DISPLAY INVISIBLE (-5950 5250);
FORCEPROP 1 LAST PATH I280
J 0
(-6277 5375);
DISPLAY 0.872340 (-6277 5375);
PAINT GREEN (-6277 5375);
DISPLAY INVISIBLE (-6277 5375);
FORCEADD TAP..1
(-6275 5425);
FORCEPROP 3 LASTPIN (-6325 5425) SIG_NAME M_E_CPU0_SA_DQ<28>
J 0
(-6315 5435);
DISPLAY 0.659574 (-6315 5435);
PAINT MONO (-6315 5435);
DISPLAY INVISIBLE (-6315 5435);
FORCEPROP 1 LASTPIN (-6325 5425) BN 28
J 0
(-6337 5433);
DISPLAY 0.489362 (-6337 5433);
PAINT GREEN (-6337 5433);
FORCEPROP 2 LAST CDS_LIB mstr_standard
J 0
(-6275 5425);
DISPLAY 0.723404 (-6275 5425);
PAINT MONO (-6275 5425);
DISPLAY INVISIBLE (-6275 5425);
FORCEPROP 1 LAST BODY_TYPE PLUMBING
J 0
(-6275 5475);
DISPLAY 0.872340 (-6275 5475);
PAINT GREEN (-6275 5475);
DISPLAY INVISIBLE (-6275 5475);
FORCEPROP 1 LAST HDL_TAP TRUE
J 0
(-5950 5300);
DISPLAY 0.872340 (-5950 5300);
DISPLAY INVISIBLE (-5950 5300);
FORCEPROP 1 LAST PATH I281
J 0
(-6277 5425);
DISPLAY 0.872340 (-6277 5425);
PAINT GREEN (-6277 5425);
DISPLAY INVISIBLE (-6277 5425);
FORCEADD TAP..1
(-6275 5525);
FORCEPROP 3 LASTPIN (-6325 5525) SIG_NAME M_E_CPU0_SA_DQ<30>
J 0
(-6315 5535);
DISPLAY 0.659574 (-6315 5535);
PAINT MONO (-6315 5535);
DISPLAY INVISIBLE (-6315 5535);
FORCEPROP 1 LASTPIN (-6325 5525) BN 30
J 0
(-6337 5533);
DISPLAY 0.489362 (-6337 5533);
PAINT GREEN (-6337 5533);
FORCEPROP 2 LAST CDS_LIB mstr_standard
J 0
(-6275 5525);
DISPLAY 0.723404 (-6275 5525);
PAINT MONO (-6275 5525);
DISPLAY INVISIBLE (-6275 5525);
FORCEPROP 1 LAST BODY_TYPE PLUMBING
J 0
(-6275 5575);
DISPLAY 0.872340 (-6275 5575);
PAINT GREEN (-6275 5575);
DISPLAY INVISIBLE (-6275 5575);
FORCEPROP 1 LAST HDL_TAP TRUE
J 0
(-5950 5400);
DISPLAY 0.872340 (-5950 5400);
DISPLAY INVISIBLE (-5950 5400);
FORCEPROP 1 LAST PATH I282
J 0
(-6277 5525);
DISPLAY 0.872340 (-6277 5525);
PAINT GREEN (-6277 5525);
DISPLAY INVISIBLE (-6277 5525);
FORCEADD TAP..1
(-6275 5475);
FORCEPROP 3 LASTPIN (-6325 5475) SIG_NAME M_E_CPU0_SA_DQ<29>
J 0
(-6315 5485);
DISPLAY 0.659574 (-6315 5485);
PAINT MONO (-6315 5485);
DISPLAY INVISIBLE (-6315 5485);
FORCEPROP 1 LASTPIN (-6325 5475) BN 29
J 0
(-6337 5483);
DISPLAY 0.489362 (-6337 5483);
PAINT GREEN (-6337 5483);
FORCEPROP 2 LAST CDS_LIB mstr_standard
J 0
(-6275 5475);
DISPLAY 0.723404 (-6275 5475);
PAINT MONO (-6275 5475);
DISPLAY INVISIBLE (-6275 5475);
FORCEPROP 1 LAST BODY_TYPE PLUMBING
J 0
(-6275 5525);
DISPLAY 0.872340 (-6275 5525);
PAINT GREEN (-6275 5525);
DISPLAY INVISIBLE (-6275 5525);
FORCEPROP 1 LAST HDL_TAP TRUE
J 0
(-5950 5350);
DISPLAY 0.872340 (-5950 5350);
DISPLAY INVISIBLE (-5950 5350);
FORCEPROP 1 LAST PATH I283
J 0
(-6277 5475);
DISPLAY 0.872340 (-6277 5475);
PAINT GREEN (-6277 5475);
DISPLAY INVISIBLE (-6277 5475);
FORCEADD OFFPAGE..3
(-5625 5650);
FORCEPROP 2 LAST $XR0 14 
J 0
(-5411 5650);
DISPLAY 0.638298 (-5411 5650);
PAINT MONO (-5411 5650);
FORCEPROP 2 LAST CDS_LIB mstr_standard
J 0
(-5625 5650);
DISPLAY 0.723404 (-5625 5650);
PAINT MONO (-5625 5650);
DISPLAY INVISIBLE (-5625 5650);
FORCEPROP 1 LAST OFFPAGE TRUE
J 0
(-5300 5525);
DISPLAY 0.872340 (-5300 5525);
PAINT GREEN (-5300 5525);
DISPLAY INVISIBLE (-5300 5525);
FORCEPROP 1 LAST COMMENT_BODY TRUE
J 0
(-5675 5550);
DISPLAY 0.872340 (-5675 5550);
PAINT GREEN (-5675 5550);
DISPLAY INVISIBLE (-5675 5550);
FORCEPROP 2 LAST PATH I284
J 0
(-5400 5700);
DISPLAY 0.808511 (-5400 5700);
DISPLAY INVISIBLE (-5400 5700);
FORCEADD Q_RES..2
(-6650 1425);
FORCEPROP 1 LAST LOCATION R5
J 0
(-6605 1550);
DISPLAY 0.489362 (-6605 1550);
PAINT SKYBLUE (-6605 1550);
FORCEPROP 2 LAST SEC 1
J 0
(-6600 1650);
DISPLAY 0.808511 (-6600 1650);
PAINT MONO (-6600 1650);
DISPLAY INVISIBLE (-6600 1650);
FORCEPROP 1 LASTPIN (-6650 1525) $PN 1
J 0
(-6645 1487);
DISPLAY 0.489362 (-6645 1487);
PAINT WHITE (-6645 1487);
FORCEPROP 1 LASTPIN (-6650 1325) $PN 2
J 0
(-6645 1335);
DISPLAY 0.489362 (-6645 1335);
PAINT WHITE (-6645 1335);
FORCEPROP 0 LASTPIN (-6650 1525) XNET_PINS 3
R 1
J 0
(-6660 1535);
DISPLAY 0.808511 (-6660 1535);
PAINT MONO (-6660 1535);
DISPLAY INVISIBLE (-6660 1535);
FORCEPROP 0 LASTPIN (-6650 1325) XNET_PINS 2
R 1
J 2
(-6660 1315);
DISPLAY 0.808511 (-6660 1315);
PAINT MONO (-6660 1315);
DISPLAY INVISIBLE (-6660 1315);
FORCEPROP 1 LAST PACK_TYPE 0402LF
J 0
(-6610 1250);
DISPLAY 0.489362 (-6610 1250);
PAINT SKYBLUE (-6610 1250);
FORCEPROP 1 LAST VALUE 54.9K
J 0
(-6605 1500);
DISPLAY 0.489362 (-6605 1500);
PAINT SKYBLUE (-6605 1500);
FORCEPROP 1 LAST TOLERANCE 1%
J 0
(-6605 1450);
DISPLAY 0.489362 (-6605 1450);
PAINT SKYBLUE (-6605 1450);
FORCEPROP 1 LAST MATERIAL CHIP
J 0
(-6610 1350);
DISPLAY 0.489362 (-6610 1350);
PAINT SKYBLUE (-6610 1350);
FORCEPROP 1 LAST WATTAGE 1/16W
J 0
(-6610 1400);
DISPLAY 0.489362 (-6610 1400);
PAINT SKYBLUE (-6610 1400);
FORCEPROP 2 LAST SEC_TYPE 0402LF
J 0
(-6600 1650);
DISPLAY 0.808511 (-6600 1650);
PAINT MONO (-6600 1650);
DISPLAY INVISIBLE (-6600 1650);
FORCEPROP 2 LAST CDS_LIB pure_quanta
J 0
(-6650 1425);
DISPLAY INVISIBLE (-6650 1425);
FORCEPROP 2 LAST BOM_COST MEM
J 0
(-6600 1600);
DISPLAY 0.808511 (-6600 1600);
DISPLAY INVISIBLE (-6600 1600);
FORCEPROP 1 LAST PATH I331
J 0
(-6600 1600);
DISPLAY 0.978723 (-6600 1600);
PAINT WHITE (-6600 1600);
DISPLAY INVISIBLE (-6600 1600);
FORCEPROP 1 LAST PART_NUMBER CS35492FB03
J 0
(-6610 1300);
DISPLAY 0.489362 (-6610 1300);
PAINT SKYBLUE (-6610 1300);
DISPLAY INVISIBLE (-6610 1300);
FORCEADD GND..1
(-6650 1200);
FORCEPROP 3 LASTPIN (-6650 1250) SIG_NAME GND\g
J 0
(-6640 1260);
DISPLAY 0.659574 (-6640 1260);
PAINT MONO (-6640 1260);
DISPLAY INVISIBLE (-6640 1260);
FORCEPROP 1 LAST SIZE 1B
J 0
(-6575 1150);
DISPLAY 0.851064 (-6575 1150);
PAINT GREEN (-6575 1150);
DISPLAY INVISIBLE (-6575 1150);
FORCEPROP 2 LAST CDS_LIB mstr_symbols
J 0
(-6650 1200);
DISPLAY 0.808511 (-6650 1200);
DISPLAY INVISIBLE (-6650 1200);
FORCEPROP 2 LAST BOM_COST MEM
J 0
(-6750 1275);
DISPLAY 0.808511 (-6750 1275);
DISPLAY INVISIBLE (-6750 1275);
FORCEPROP 1 LAST VOLTAGE 0.0
J 0
(-6695 1157);
DISPLAY 0.723404 (-6695 1157);
PAINT SKYBLUE (-6695 1157);
DISPLAY INVISIBLE (-6695 1157);
FORCEPROP 1 LAST BODY_TYPE PLUMBING
J 0
(-6695 1157);
DISPLAY 0.340426 (-6695 1157);
PAINT GREEN (-6695 1157);
DISPLAY INVISIBLE (-6695 1157);
FORCEPROP 1 LAST HDL_POWER GND
J 0
(-6650 1350);
DISPLAY 0.851064 (-6650 1350);
PAINT GREEN (-6650 1350);
DISPLAY INVISIBLE (-6650 1350);
FORCEPROP 1 LAST PATH I332
J 0
(-6575 1200);
DISPLAY 0.872340 (-6575 1200);
PAINT GREEN (-6575 1200);
DISPLAY INVISIBLE (-6575 1200);
FORCEADD OFFPAGE..5
(-7425 1600);
FORCEPROP 2 LAST $XR0 90 
J 0
(-7649 1600);
DISPLAY 0.638298 (-7649 1600);
PAINT MONO (-7649 1600);
FORCEPROP 2 LAST CDS_LIB mstr_standard
J 0
(-7425 1600);
DISPLAY 0.808511 (-7425 1600);
DISPLAY INVISIBLE (-7425 1600);
FORCEPROP 2 LAST BOM_COST MEM
J 0
(-7500 1675);
DISPLAY 0.808511 (-7500 1675);
DISPLAY INVISIBLE (-7500 1675);
FORCEPROP 1 LAST OFFPAGE TRUE
J 0
(-7100 1475);
DISPLAY 0.872340 (-7100 1475);
PAINT GREEN (-7100 1475);
DISPLAY INVISIBLE (-7100 1475);
FORCEPROP 1 LAST COMMENT_BODY TRUE
J 0
(-7325 1525);
DISPLAY 0.872340 (-7325 1525);
PAINT GREEN (-7325 1525);
DISPLAY INVISIBLE (-7325 1525);
FORCEPROP 2 LAST PATH I333
J 0
(-7375 1675);
DISPLAY 0.808511 (-7375 1675);
DISPLAY INVISIBLE (-7375 1675);
FORCEADD OFFPAGE..1
(-8575 3075);
FORCEPROP 2 LAST $XR0 90 
J 0
(-8826 3075);
DISPLAY 0.638298 (-8826 3075);
PAINT MONO (-8826 3075);
FORCEPROP 2 LAST CDS_LIB mstr_standard
J 0
(-8575 3075);
DISPLAY 0.808511 (-8575 3075);
DISPLAY INVISIBLE (-8575 3075);
FORCEPROP 1 LAST OFFPAGE TRUE
J 0
(-8250 2950);
DISPLAY 0.872340 (-8250 2950);
PAINT GREEN (-8250 2950);
DISPLAY INVISIBLE (-8250 2950);
FORCEPROP 1 LAST COMMENT_BODY TRUE
J 0
(-8450 2975);
DISPLAY 0.872340 (-8450 2975);
PAINT GREEN (-8450 2975);
DISPLAY INVISIBLE (-8450 2975);
FORCEPROP 2 LAST PATH I334
J 0
(-8525 3150);
DISPLAY 0.808511 (-8525 3150);
DISPLAY INVISIBLE (-8525 3150);
FORCEADD SCONN288_DDR506112002KQ..1
(-7125 3825);
FORCEPROP 1 LAST LOCATION J21
J 0
(-7575 5900);
DISPLAY 0.468085 (-7575 5900);
PAINT SKYBLUE (-7575 5900);
FORCEPROP 0 LAST $SEC 1
J 0
(-7575 6050);
DISPLAY 0.680851 (-7575 6050);
PAINT MONO (-7575 6050);
DISPLAY INVISIBLE (-7575 6050);
FORCEPROP 2 LAST CDS_SEC 1
J 0
(-7575 6050);
DISPLAY 1.021277 (-7575 6050);
DISPLAY INVISIBLE (-7575 6050);
FORCEPROP 0 LASTPIN (-7725 3225) $PN 62
J 2
(-7735 3235);
DISPLAY 0.680851 (-7735 3235);
PAINT MONO (-7735 3235);
FORCEPROP 0 LASTPIN (-7725 5275) $PN 66
J 2
(-7735 5285);
DISPLAY 0.680851 (-7735 5285);
PAINT MONO (-7735 5285);
FORCEPROP 0 LASTPIN (-7725 4875) $PN 76
J 2
(-7735 4885);
DISPLAY 0.680851 (-7735 4885);
PAINT MONO (-7735 4885);
FORCEPROP 0 LASTPIN (-7725 5325) $PN 211
J 2
(-7735 5335);
DISPLAY 0.680851 (-7735 5335);
PAINT MONO (-7735 5335);
FORCEPROP 0 LASTPIN (-7725 4925) $PN 221
J 2
(-7735 4935);
DISPLAY 0.680851 (-7735 4935);
PAINT MONO (-7735 4935);
FORCEPROP 0 LASTPIN (-7725 5375) $PN 68
J 2
(-7735 5385);
DISPLAY 0.680851 (-7735 5385);
PAINT MONO (-7735 5385);
FORCEPROP 0 LASTPIN (-7725 4975) $PN 78
J 2
(-7735 4985);
DISPLAY 0.680851 (-7735 4985);
PAINT MONO (-7735 4985);
FORCEPROP 0 LASTPIN (-7725 5425) $PN 213
J 2
(-7735 5435);
DISPLAY 0.680851 (-7735 5435);
PAINT MONO (-7735 5435);
FORCEPROP 0 LASTPIN (-7725 5025) $PN 223
J 2
(-7735 5035);
DISPLAY 0.680851 (-7735 5035);
PAINT MONO (-7735 5035);
FORCEPROP 0 LASTPIN (-7725 5475) $PN 70
J 2
(-7735 5485);
DISPLAY 0.680851 (-7735 5485);
PAINT MONO (-7735 5485);
FORCEPROP 0 LASTPIN (-7725 5075) $PN 80
J 2
(-7735 5085);
DISPLAY 0.680851 (-7735 5085);
PAINT MONO (-7735 5085);
FORCEPROP 0 LASTPIN (-7725 5525) $PN 215
J 2
(-7735 5535);
DISPLAY 0.680851 (-7735 5535);
PAINT MONO (-7735 5535);
FORCEPROP 0 LASTPIN (-7725 5125) $PN 225
J 2
(-7735 5135);
DISPLAY 0.680851 (-7735 5135);
PAINT MONO (-7735 5135);
FORCEPROP 0 LASTPIN (-7725 5575) $PN 72
J 2
(-7735 5585);
DISPLAY 0.680851 (-7735 5585);
PAINT MONO (-7735 5585);
FORCEPROP 0 LASTPIN (-7725 5175) $PN 82
J 2
(-7735 5185);
DISPLAY 0.680851 (-7735 5185);
PAINT MONO (-7735 5185);
FORCEPROP 0 LASTPIN (-7725 3825) $PN 51
J 2
(-7735 3835);
DISPLAY 0.680851 (-7735 3835);
PAINT MONO (-7735 3835);
FORCEPROP 0 LASTPIN (-7725 3375) $PN 96
J 2
(-7735 3385);
DISPLAY 0.680851 (-7735 3385);
PAINT MONO (-7735 3385);
FORCEPROP 0 LASTPIN (-7725 3875) $PN 53
J 2
(-7735 3885);
DISPLAY 0.680851 (-7735 3885);
PAINT MONO (-7735 3885);
FORCEPROP 0 LASTPIN (-7725 3425) $PN 98
J 2
(-7735 3435);
DISPLAY 0.680851 (-7735 3435);
PAINT MONO (-7735 3435);
FORCEPROP 0 LASTPIN (-7725 3925) $PN 196
J 2
(-7735 3935);
DISPLAY 0.680851 (-7735 3935);
PAINT MONO (-7735 3935);
FORCEPROP 0 LASTPIN (-7725 3475) $PN 241
J 2
(-7735 3485);
DISPLAY 0.680851 (-7735 3485);
PAINT MONO (-7735 3485);
FORCEPROP 0 LASTPIN (-7725 3975) $PN 198
J 2
(-7735 3985);
DISPLAY 0.680851 (-7735 3985);
PAINT MONO (-7735 3985);
FORCEPROP 0 LASTPIN (-7725 3525) $PN 243
J 2
(-7735 3535);
DISPLAY 0.680851 (-7735 3535);
PAINT MONO (-7735 3535);
FORCEPROP 0 LASTPIN (-7725 4025) $PN 58
J 2
(-7735 4035);
DISPLAY 0.680851 (-7735 4035);
PAINT MONO (-7735 4035);
FORCEPROP 0 LASTPIN (-7725 3575) $PN 89
J 2
(-7735 3585);
DISPLAY 0.680851 (-7735 3585);
PAINT MONO (-7735 3585);
FORCEPROP 0 LASTPIN (-7725 4075) $PN 60
J 2
(-7735 4085);
DISPLAY 0.680851 (-7735 4085);
PAINT MONO (-7735 4085);
FORCEPROP 0 LASTPIN (-7725 3625) $PN 91
J 2
(-7735 3635);
DISPLAY 0.680851 (-7735 3635);
PAINT MONO (-7735 3635);
FORCEPROP 0 LASTPIN (-7725 4125) $PN 203
J 2
(-7735 4135);
DISPLAY 0.680851 (-7735 4135);
PAINT MONO (-7735 4135);
FORCEPROP 0 LASTPIN (-7725 3675) $PN 234
J 2
(-7735 3685);
DISPLAY 0.680851 (-7735 3685);
PAINT MONO (-7735 3685);
FORCEPROP 0 LASTPIN (-7725 4175) $PN 205
J 2
(-7735 4185);
DISPLAY 0.680851 (-7735 4185);
PAINT MONO (-7735 4185);
FORCEPROP 0 LASTPIN (-7725 3725) $PN 236
J 2
(-7735 3735);
DISPLAY 0.680851 (-7735 3735);
PAINT MONO (-7735 3735);
FORCEPROP 0 LASTPIN (-7725 4275) $PN 218
J 2
(-7735 4285);
DISPLAY 0.680851 (-7735 4285);
PAINT MONO (-7735 4285);
FORCEPROP 0 LASTPIN (-7725 4325) $PN 217
J 2
(-7735 4335);
DISPLAY 0.680851 (-7735 4335);
PAINT MONO (-7735 4335);
FORCEPROP 0 LASTPIN (-7725 4575) $PN 64
J 2
(-7735 4585);
DISPLAY 0.680851 (-7735 4585);
PAINT MONO (-7735 4585);
FORCEPROP 0 LASTPIN (-7725 4425) $PN 84
J 2
(-7735 4435);
DISPLAY 0.680851 (-7735 4435);
PAINT MONO (-7735 4435);
FORCEPROP 0 LASTPIN (-7725 4625) $PN 209
J 2
(-7735 4635);
DISPLAY 0.680851 (-7735 4635);
PAINT MONO (-7735 4635);
FORCEPROP 0 LASTPIN (-7725 4475) $PN 229
J 2
(-7735 4485);
DISPLAY 0.680851 (-7735 4485);
PAINT MONO (-7735 4485);
FORCEPROP 0 LASTPIN (-6525 4025) $PN 7
J 0
(-6515 4035);
DISPLAY 0.680851 (-6515 4035);
PAINT MONO (-6515 4035);
FORCEPROP 0 LASTPIN (-6525 2375) $PN 100
J 0
(-6515 2385);
DISPLAY 0.680851 (-6515 2385);
PAINT MONO (-6515 2385);
FORCEPROP 0 LASTPIN (-6525 4075) $PN 9
J 0
(-6515 4085);
DISPLAY 0.680851 (-6515 4085);
PAINT MONO (-6515 4085);
FORCEPROP 0 LASTPIN (-6525 2425) $PN 102
J 0
(-6515 2435);
DISPLAY 0.680851 (-6515 2435);
PAINT MONO (-6515 2435);
FORCEPROP 0 LASTPIN (-6525 4125) $PN 152
J 0
(-6515 4135);
DISPLAY 0.680851 (-6515 4135);
PAINT MONO (-6515 4135);
FORCEPROP 0 LASTPIN (-6525 2475) $PN 245
J 0
(-6515 2485);
DISPLAY 0.680851 (-6515 2485);
PAINT MONO (-6515 2485);
FORCEPROP 0 LASTPIN (-6525 4175) $PN 154
J 0
(-6515 4185);
DISPLAY 0.680851 (-6515 4185);
PAINT MONO (-6515 4185);
FORCEPROP 0 LASTPIN (-6525 2525) $PN 247
J 0
(-6515 2535);
DISPLAY 0.680851 (-6515 2535);
PAINT MONO (-6515 2535);
FORCEPROP 0 LASTPIN (-6525 4225) $PN 14
J 0
(-6515 4235);
DISPLAY 0.680851 (-6515 4235);
PAINT MONO (-6515 4235);
FORCEPROP 0 LASTPIN (-6525 2575) $PN 107
J 0
(-6515 2585);
DISPLAY 0.680851 (-6515 2585);
PAINT MONO (-6515 2585);
FORCEPROP 0 LASTPIN (-6525 4275) $PN 16
J 0
(-6515 4285);
DISPLAY 0.680851 (-6515 4285);
PAINT MONO (-6515 4285);
FORCEPROP 0 LASTPIN (-6525 2625) $PN 109
J 0
(-6515 2635);
DISPLAY 0.680851 (-6515 2635);
PAINT MONO (-6515 2635);
FORCEPROP 0 LASTPIN (-6525 4325) $PN 159
J 0
(-6515 4335);
DISPLAY 0.680851 (-6515 4335);
PAINT MONO (-6515 4335);
FORCEPROP 0 LASTPIN (-6525 2675) $PN 252
J 0
(-6515 2685);
DISPLAY 0.680851 (-6515 2685);
PAINT MONO (-6515 2685);
FORCEPROP 0 LASTPIN (-6525 4375) $PN 161
J 0
(-6515 4385);
DISPLAY 0.680851 (-6515 4385);
PAINT MONO (-6515 4385);
FORCEPROP 0 LASTPIN (-6525 2725) $PN 254
J 0
(-6515 2735);
DISPLAY 0.680851 (-6515 2735);
PAINT MONO (-6515 2735);
FORCEPROP 0 LASTPIN (-6525 4425) $PN 18
J 0
(-6515 4435);
DISPLAY 0.680851 (-6515 4435);
PAINT MONO (-6515 4435);
FORCEPROP 0 LASTPIN (-6525 2775) $PN 111
J 0
(-6515 2785);
DISPLAY 0.680851 (-6515 2785);
PAINT MONO (-6515 2785);
FORCEPROP 0 LASTPIN (-6525 4475) $PN 20
J 0
(-6515 4485);
DISPLAY 0.680851 (-6515 4485);
PAINT MONO (-6515 4485);
FORCEPROP 0 LASTPIN (-6525 2825) $PN 113
J 0
(-6515 2835);
DISPLAY 0.680851 (-6515 2835);
PAINT MONO (-6515 2835);
FORCEPROP 0 LASTPIN (-6525 4525) $PN 163
J 0
(-6515 4535);
DISPLAY 0.680851 (-6515 4535);
PAINT MONO (-6515 4535);
FORCEPROP 0 LASTPIN (-6525 2875) $PN 256
J 0
(-6515 2885);
DISPLAY 0.680851 (-6515 2885);
PAINT MONO (-6515 2885);
FORCEPROP 0 LASTPIN (-6525 4575) $PN 165
J 0
(-6515 4585);
DISPLAY 0.680851 (-6515 4585);
PAINT MONO (-6515 4585);
FORCEPROP 0 LASTPIN (-6525 2925) $PN 258
J 0
(-6515 2935);
DISPLAY 0.680851 (-6515 2935);
PAINT MONO (-6515 2935);
FORCEPROP 0 LASTPIN (-6525 4625) $PN 25
J 0
(-6515 4635);
DISPLAY 0.680851 (-6515 4635);
PAINT MONO (-6515 4635);
FORCEPROP 0 LASTPIN (-6525 2975) $PN 118
J 0
(-6515 2985);
DISPLAY 0.680851 (-6515 2985);
PAINT MONO (-6515 2985);
FORCEPROP 0 LASTPIN (-6525 4675) $PN 27
J 0
(-6515 4685);
DISPLAY 0.680851 (-6515 4685);
PAINT MONO (-6515 4685);
FORCEPROP 0 LASTPIN (-6525 3025) $PN 120
J 0
(-6515 3035);
DISPLAY 0.680851 (-6515 3035);
PAINT MONO (-6515 3035);
FORCEPROP 0 LASTPIN (-6525 4725) $PN 170
J 0
(-6515 4735);
DISPLAY 0.680851 (-6515 4735);
PAINT MONO (-6515 4735);
FORCEPROP 0 LASTPIN (-6525 3075) $PN 263
J 0
(-6515 3085);
DISPLAY 0.680851 (-6515 3085);
PAINT MONO (-6515 3085);
FORCEPROP 0 LASTPIN (-6525 4775) $PN 172
J 0
(-6515 4785);
DISPLAY 0.680851 (-6515 4785);
PAINT MONO (-6515 4785);
FORCEPROP 0 LASTPIN (-6525 3125) $PN 265
J 0
(-6515 3135);
DISPLAY 0.680851 (-6515 3135);
PAINT MONO (-6515 3135);
FORCEPROP 0 LASTPIN (-6525 4825) $PN 29
J 0
(-6515 4835);
DISPLAY 0.680851 (-6515 4835);
PAINT MONO (-6515 4835);
FORCEPROP 0 LASTPIN (-6525 3175) $PN 122
J 0
(-6515 3185);
DISPLAY 0.680851 (-6515 3185);
PAINT MONO (-6515 3185);
FORCEPROP 0 LASTPIN (-6525 4875) $PN 31
J 0
(-6515 4885);
DISPLAY 0.680851 (-6515 4885);
PAINT MONO (-6515 4885);
FORCEPROP 0 LASTPIN (-6525 3225) $PN 124
J 0
(-6515 3235);
DISPLAY 0.680851 (-6515 3235);
PAINT MONO (-6515 3235);
FORCEPROP 0 LASTPIN (-6525 4925) $PN 174
J 0
(-6515 4935);
DISPLAY 0.680851 (-6515 4935);
PAINT MONO (-6515 4935);
FORCEPROP 0 LASTPIN (-6525 3275) $PN 267
J 0
(-6515 3285);
DISPLAY 0.680851 (-6515 3285);
PAINT MONO (-6515 3285);
FORCEPROP 0 LASTPIN (-6525 4975) $PN 176
J 0
(-6515 4985);
DISPLAY 0.680851 (-6515 4985);
PAINT MONO (-6515 4985);
FORCEPROP 0 LASTPIN (-6525 3325) $PN 269
J 0
(-6515 3335);
DISPLAY 0.680851 (-6515 3335);
PAINT MONO (-6515 3335);
FORCEPROP 0 LASTPIN (-6525 5025) $PN 36
J 0
(-6515 5035);
DISPLAY 0.680851 (-6515 5035);
PAINT MONO (-6515 5035);
FORCEPROP 0 LASTPIN (-6525 3375) $PN 129
J 0
(-6515 3385);
DISPLAY 0.680851 (-6515 3385);
PAINT MONO (-6515 3385);
FORCEPROP 0 LASTPIN (-6525 5075) $PN 38
J 0
(-6515 5085);
DISPLAY 0.680851 (-6515 5085);
PAINT MONO (-6515 5085);
FORCEPROP 0 LASTPIN (-6525 3425) $PN 131
J 0
(-6515 3435);
DISPLAY 0.680851 (-6515 3435);
PAINT MONO (-6515 3435);
FORCEPROP 0 LASTPIN (-6525 5125) $PN 181
J 0
(-6515 5135);
DISPLAY 0.680851 (-6515 5135);
PAINT MONO (-6515 5135);
FORCEPROP 0 LASTPIN (-6525 3475) $PN 274
J 0
(-6515 3485);
DISPLAY 0.680851 (-6515 3485);
PAINT MONO (-6515 3485);
FORCEPROP 0 LASTPIN (-6525 5175) $PN 183
J 0
(-6515 5185);
DISPLAY 0.680851 (-6515 5185);
PAINT MONO (-6515 5185);
FORCEPROP 0 LASTPIN (-6525 3525) $PN 276
J 0
(-6515 3535);
DISPLAY 0.680851 (-6515 3535);
PAINT MONO (-6515 3535);
FORCEPROP 0 LASTPIN (-6525 5225) $PN 40
J 0
(-6515 5235);
DISPLAY 0.680851 (-6515 5235);
PAINT MONO (-6515 5235);
FORCEPROP 0 LASTPIN (-6525 3575) $PN 133
J 0
(-6515 3585);
DISPLAY 0.680851 (-6515 3585);
PAINT MONO (-6515 3585);
FORCEPROP 0 LASTPIN (-6525 5275) $PN 42
J 0
(-6515 5285);
DISPLAY 0.680851 (-6515 5285);
PAINT MONO (-6515 5285);
FORCEPROP 0 LASTPIN (-6525 3625) $PN 135
J 0
(-6515 3635);
DISPLAY 0.680851 (-6515 3635);
PAINT MONO (-6515 3635);
FORCEPROP 0 LASTPIN (-6525 5325) $PN 185
J 0
(-6515 5335);
DISPLAY 0.680851 (-6515 5335);
PAINT MONO (-6515 5335);
FORCEPROP 0 LASTPIN (-6525 3675) $PN 278
J 0
(-6515 3685);
DISPLAY 0.680851 (-6515 3685);
PAINT MONO (-6515 3685);
FORCEPROP 0 LASTPIN (-6525 5375) $PN 187
J 0
(-6515 5385);
DISPLAY 0.680851 (-6515 5385);
PAINT MONO (-6515 5385);
FORCEPROP 0 LASTPIN (-6525 3725) $PN 280
J 0
(-6515 3735);
DISPLAY 0.680851 (-6515 3735);
PAINT MONO (-6515 3735);
FORCEPROP 0 LASTPIN (-6525 5425) $PN 47
J 0
(-6515 5435);
DISPLAY 0.680851 (-6515 5435);
PAINT MONO (-6515 5435);
FORCEPROP 0 LASTPIN (-6525 3775) $PN 140
J 0
(-6515 3785);
DISPLAY 0.680851 (-6515 3785);
PAINT MONO (-6515 3785);
FORCEPROP 0 LASTPIN (-6525 5475) $PN 49
J 0
(-6515 5485);
DISPLAY 0.680851 (-6515 5485);
PAINT MONO (-6515 5485);
FORCEPROP 0 LASTPIN (-6525 3825) $PN 142
J 0
(-6515 3835);
DISPLAY 0.680851 (-6515 3835);
PAINT MONO (-6515 3835);
FORCEPROP 0 LASTPIN (-6525 5525) $PN 192
J 0
(-6515 5535);
DISPLAY 0.680851 (-6515 5535);
PAINT MONO (-6515 5535);
FORCEPROP 0 LASTPIN (-6525 3875) $PN 285
J 0
(-6515 3885);
DISPLAY 0.680851 (-6515 3885);
PAINT MONO (-6515 3885);
FORCEPROP 0 LASTPIN (-6525 5575) $PN 194
J 0
(-6515 5585);
DISPLAY 0.680851 (-6515 5585);
PAINT MONO (-6515 5585);
FORCEPROP 0 LASTPIN (-6525 3925) $PN 287
J 0
(-6515 3935);
DISPLAY 0.680851 (-6515 3935);
PAINT MONO (-6515 3935);
FORCEPROP 0 LASTPIN (-7725 3075) $PN 148
J 2
(-7735 3085);
DISPLAY 0.680851 (-7735 3085);
PAINT MONO (-7735 3085);
FORCEPROP 0 LASTPIN (-7725 2975) $PN 4
J 2
(-7735 2985);
DISPLAY 0.680851 (-7735 2985);
PAINT MONO (-7735 2985);
FORCEPROP 0 LASTPIN (-7725 3025) $PN 5
J 2
(-7735 3035);
DISPLAY 0.680851 (-7735 3035);
PAINT MONO (-7735 3035);
FORCEPROP 0 LASTPIN (-7725 2175) $PN 86
J 2
(-7735 2185);
DISPLAY 0.680851 (-7735 2185);
PAINT MONO (-7735 2185);
FORCEPROP 0 LASTPIN (-7725 2125) $PN 87
J 2
(-7735 2135);
DISPLAY 0.680851 (-7735 2135);
PAINT MONO (-7735 2135);
FORCEPROP 0 LASTPIN (-7725 4775) $PN 74
J 2
(-7735 4785);
DISPLAY 0.680851 (-7735 4785);
PAINT MONO (-7735 4785);
FORCEPROP 0 LASTPIN (-7725 4725) $PN 227
J 2
(-7735 4735);
DISPLAY 0.680851 (-7735 4735);
PAINT MONO (-7735 4735);
FORCEPROP 0 LASTPIN (-7725 2725) $PN 147
J 2
(-7735 2735);
DISPLAY 0.680851 (-7735 2735);
PAINT MONO (-7735 2735);
FORCEPROP 0 LASTPIN (-7725 3275) $PN 207
J 2
(-7735 3285);
DISPLAY 0.680851 (-7735 3285);
PAINT MONO (-7735 3285);
FORCEPROP 0 LASTPIN (-7725 2325) $PN 2
J 2
(-7735 2335);
DISPLAY 0.680851 (-7735 2335);
PAINT MONO (-7735 2335);
FORCEPROP 0 LASTPIN (-7725 2375) $PN 144
J 2
(-7735 2385);
DISPLAY 0.680851 (-7735 2385);
PAINT MONO (-7735 2385);
FORCEPROP 0 LASTPIN (-7725 2425) $PN 149
J 2
(-7735 2435);
DISPLAY 0.680851 (-7735 2435);
PAINT MONO (-7735 2435);
FORCEPROP 0 LASTPIN (-7725 2475) $PN 150
J 2
(-7735 2485);
DISPLAY 0.680851 (-7735 2485);
PAINT MONO (-7735 2485);
FORCEPROP 0 LASTPIN (-7725 2525) $PN 220
J 2
(-7735 2535);
DISPLAY 0.680851 (-7735 2535);
PAINT MONO (-7735 2535);
FORCEPROP 0 LASTPIN (-7725 2575) $PN 231
J 2
(-7735 2585);
DISPLAY 0.680851 (-7735 2585);
PAINT MONO (-7735 2585);
FORCEPROP 0 LASTPIN (-7725 2625) $PN 232
J 2
(-7735 2635);
DISPLAY 0.680851 (-7735 2635);
PAINT MONO (-7735 2635);
FORCEPROP 0 LASTPIN (-7725 3125) $PN 3
J 2
(-7735 3135);
DISPLAY 0.680851 (-7735 3135);
PAINT MONO (-7735 3135);
FORCEPROP 2 LAST PART_TYPE SMLF
J 0
(-7575 6000);
DISPLAY 1.021277 (-7575 6000);
FORCEPROP 2 LAST VALUE SCONN288_DDR506112002KQ
J 0
(-7575 5950);
DISPLAY 0.489362 (-7575 5950);
PAINT SKYBLUE (-7575 5950);
FORCEPROP 1 LAST MATERIAL IO
J 0
(-7575 5750);
DISPLAY 0.468085 (-7575 5750);
PAINT SKYBLUE (-7575 5750);
FORCEPROP 1 LAST CDS_LMAN_SYM_OUTLINE -450,1900,450,-1850
J 0
(-7125 3825);
DISPLAY 0.468085 (-7125 3825);
PAINT GREEN (-7125 3825);
DISPLAY INVISIBLE (-7125 3825);
FORCEPROP 1 LAST NEEDS_NO_SIZE TRUE
J 0
(-7125 3825);
DISPLAY 0.723404 (-7125 3825);
PAINT GREEN (-7125 3825);
DISPLAY INVISIBLE (-7125 3825);
FORCEPROP 2 LAST CDS_LIB pure_quanta
J 0
(-7125 3825);
DISPLAY INVISIBLE (-7125 3825);
FORCEPROP 1 LAST PATH I348
J 0
(-7125 3825);
DISPLAY 0.723404 (-7125 3825);
PAINT GREEN (-7125 3825);
DISPLAY INVISIBLE (-7125 3825);
FORCEPROP 1 LAST PART_NUMBER DFHST8FS479
J 0
(-7575 5825);
DISPLAY 0.468085 (-7575 5825);
PAINT SKYBLUE (-7575 5825);
DISPLAY INVISIBLE (-7575 5825);
FORCEADD SCONN288_DDR506112002KQ..3
(-1400 3925);
FORCEPROP 1 LAST LOCATION J21
J 0
(-1850 5900);
DISPLAY 0.468085 (-1850 5900);
PAINT SKYBLUE (-1850 5900);
FORCEPROP 0 LAST $SEC 3
J 0
(-1850 6050);
DISPLAY 0.680851 (-1850 6050);
PAINT MONO (-1850 6050);
DISPLAY INVISIBLE (-1850 6050);
FORCEPROP 2 LAST CDS_SEC 3
J 0
(-1850 6050);
DISPLAY 1.021277 (-1850 6050);
DISPLAY INVISIBLE (-1850 6050);
FORCEPROP 0 LASTPIN (-800 2325) $PN G1
J 0
(-790 2335);
DISPLAY 0.680851 (-790 2335);
PAINT MONO (-790 2335);
FORCEPROP 0 LASTPIN (-800 2275) $PN G2
J 0
(-790 2285);
DISPLAY 0.680851 (-790 2285);
PAINT MONO (-790 2285);
FORCEPROP 0 LASTPIN (-800 2225) $PN G3
J 0
(-790 2235);
DISPLAY 0.680851 (-790 2235);
PAINT MONO (-790 2235);
FORCEPROP 0 LASTPIN (-2000 5475) $PN 1
J 2
(-2010 5485);
DISPLAY 0.680851 (-2010 5485);
PAINT MONO (-2010 5485);
FORCEPROP 0 LASTPIN (-2000 5525) $PN 145
J 2
(-2010 5535);
DISPLAY 0.680851 (-2010 5535);
PAINT MONO (-2010 5535);
FORCEPROP 0 LASTPIN (-2000 5575) $PN 146
J 2
(-2010 5585);
DISPLAY 0.680851 (-2010 5585);
PAINT MONO (-2010 5585);
FORCEPROP 0 LASTPIN (-800 2425) $PN 6
J 0
(-790 2435);
DISPLAY 0.680851 (-790 2435);
PAINT MONO (-790 2435);
FORCEPROP 0 LASTPIN (-800 2475) $PN 8
J 0
(-790 2485);
DISPLAY 0.680851 (-790 2485);
PAINT MONO (-790 2485);
FORCEPROP 0 LASTPIN (-800 2525) $PN 10
J 0
(-790 2535);
DISPLAY 0.680851 (-790 2535);
PAINT MONO (-790 2535);
FORCEPROP 0 LASTPIN (-800 2575) $PN 13
J 0
(-790 2585);
DISPLAY 0.680851 (-790 2585);
PAINT MONO (-790 2585);
FORCEPROP 0 LASTPIN (-800 2625) $PN 15
J 0
(-790 2635);
DISPLAY 0.680851 (-790 2635);
PAINT MONO (-790 2635);
FORCEPROP 0 LASTPIN (-800 2675) $PN 17
J 0
(-790 2685);
DISPLAY 0.680851 (-790 2685);
PAINT MONO (-790 2685);
FORCEPROP 0 LASTPIN (-800 2725) $PN 19
J 0
(-790 2735);
DISPLAY 0.680851 (-790 2735);
PAINT MONO (-790 2735);
FORCEPROP 0 LASTPIN (-800 2775) $PN 21
J 0
(-790 2785);
DISPLAY 0.680851 (-790 2785);
PAINT MONO (-790 2785);
FORCEPROP 0 LASTPIN (-800 2825) $PN 24
J 0
(-790 2835);
DISPLAY 0.680851 (-790 2835);
PAINT MONO (-790 2835);
FORCEPROP 0 LASTPIN (-800 2875) $PN 26
J 0
(-790 2885);
DISPLAY 0.680851 (-790 2885);
PAINT MONO (-790 2885);
FORCEPROP 0 LASTPIN (-800 2925) $PN 28
J 0
(-790 2935);
DISPLAY 0.680851 (-790 2935);
PAINT MONO (-790 2935);
FORCEPROP 0 LASTPIN (-800 2975) $PN 30
J 0
(-790 2985);
DISPLAY 0.680851 (-790 2985);
PAINT MONO (-790 2985);
FORCEPROP 0 LASTPIN (-800 3025) $PN 32
J 0
(-790 3035);
DISPLAY 0.680851 (-790 3035);
PAINT MONO (-790 3035);
FORCEPROP 0 LASTPIN (-800 3075) $PN 35
J 0
(-790 3085);
DISPLAY 0.680851 (-790 3085);
PAINT MONO (-790 3085);
FORCEPROP 0 LASTPIN (-800 3125) $PN 37
J 0
(-790 3135);
DISPLAY 0.680851 (-790 3135);
PAINT MONO (-790 3135);
FORCEPROP 0 LASTPIN (-800 3175) $PN 39
J 0
(-790 3185);
DISPLAY 0.680851 (-790 3185);
PAINT MONO (-790 3185);
FORCEPROP 0 LASTPIN (-800 3225) $PN 41
J 0
(-790 3235);
DISPLAY 0.680851 (-790 3235);
PAINT MONO (-790 3235);
FORCEPROP 0 LASTPIN (-800 3275) $PN 43
J 0
(-790 3285);
DISPLAY 0.680851 (-790 3285);
PAINT MONO (-790 3285);
FORCEPROP 0 LASTPIN (-800 3325) $PN 46
J 0
(-790 3335);
DISPLAY 0.680851 (-790 3335);
PAINT MONO (-790 3335);
FORCEPROP 0 LASTPIN (-800 3375) $PN 48
J 0
(-790 3385);
DISPLAY 0.680851 (-790 3385);
PAINT MONO (-790 3385);
FORCEPROP 0 LASTPIN (-800 3425) $PN 50
J 0
(-790 3435);
DISPLAY 0.680851 (-790 3435);
PAINT MONO (-790 3435);
FORCEPROP 0 LASTPIN (-800 3475) $PN 52
J 0
(-790 3485);
DISPLAY 0.680851 (-790 3485);
PAINT MONO (-790 3485);
FORCEPROP 0 LASTPIN (-800 3525) $PN 54
J 0
(-790 3535);
DISPLAY 0.680851 (-790 3535);
PAINT MONO (-790 3535);
FORCEPROP 0 LASTPIN (-800 3575) $PN 57
J 0
(-790 3585);
DISPLAY 0.680851 (-790 3585);
PAINT MONO (-790 3585);
FORCEPROP 0 LASTPIN (-800 3625) $PN 59
J 0
(-790 3635);
DISPLAY 0.680851 (-790 3635);
PAINT MONO (-790 3635);
FORCEPROP 0 LASTPIN (-800 3675) $PN 61
J 0
(-790 3685);
DISPLAY 0.680851 (-790 3685);
PAINT MONO (-790 3685);
FORCEPROP 0 LASTPIN (-800 3725) $PN 63
J 0
(-790 3735);
DISPLAY 0.680851 (-790 3735);
PAINT MONO (-790 3735);
FORCEPROP 0 LASTPIN (-800 3775) $PN 65
J 0
(-790 3785);
DISPLAY 0.680851 (-790 3785);
PAINT MONO (-790 3785);
FORCEPROP 0 LASTPIN (-800 3825) $PN 67
J 0
(-790 3835);
DISPLAY 0.680851 (-790 3835);
PAINT MONO (-790 3835);
FORCEPROP 0 LASTPIN (-800 3875) $PN 69
J 0
(-790 3885);
DISPLAY 0.680851 (-790 3885);
PAINT MONO (-790 3885);
FORCEPROP 0 LASTPIN (-800 3925) $PN 71
J 0
(-790 3935);
DISPLAY 0.680851 (-790 3935);
PAINT MONO (-790 3935);
FORCEPROP 0 LASTPIN (-800 3975) $PN 73
J 0
(-790 3985);
DISPLAY 0.680851 (-790 3985);
PAINT MONO (-790 3985);
FORCEPROP 0 LASTPIN (-800 4025) $PN 75
J 0
(-790 4035);
DISPLAY 0.680851 (-790 4035);
PAINT MONO (-790 4035);
FORCEPROP 0 LASTPIN (-800 4075) $PN 77
J 0
(-790 4085);
DISPLAY 0.680851 (-790 4085);
PAINT MONO (-790 4085);
FORCEPROP 0 LASTPIN (-800 4125) $PN 79
J 0
(-790 4135);
DISPLAY 0.680851 (-790 4135);
PAINT MONO (-790 4135);
FORCEPROP 0 LASTPIN (-800 4175) $PN 81
J 0
(-790 4185);
DISPLAY 0.680851 (-790 4185);
PAINT MONO (-790 4185);
FORCEPROP 0 LASTPIN (-800 4225) $PN 83
J 0
(-790 4235);
DISPLAY 0.680851 (-790 4235);
PAINT MONO (-790 4235);
FORCEPROP 0 LASTPIN (-800 4275) $PN 85
J 0
(-790 4285);
DISPLAY 0.680851 (-790 4285);
PAINT MONO (-790 4285);
FORCEPROP 0 LASTPIN (-800 4325) $PN 88
J 0
(-790 4335);
DISPLAY 0.680851 (-790 4335);
PAINT MONO (-790 4335);
FORCEPROP 0 LASTPIN (-800 4375) $PN 90
J 0
(-790 4385);
DISPLAY 0.680851 (-790 4385);
PAINT MONO (-790 4385);
FORCEPROP 0 LASTPIN (-800 4425) $PN 92
J 0
(-790 4435);
DISPLAY 0.680851 (-790 4435);
PAINT MONO (-790 4435);
FORCEPROP 0 LASTPIN (-800 4475) $PN 95
J 0
(-790 4485);
DISPLAY 0.680851 (-790 4485);
PAINT MONO (-790 4485);
FORCEPROP 0 LASTPIN (-800 4525) $PN 97
J 0
(-790 4535);
DISPLAY 0.680851 (-790 4535);
PAINT MONO (-790 4535);
FORCEPROP 0 LASTPIN (-800 4575) $PN 99
J 0
(-790 4585);
DISPLAY 0.680851 (-790 4585);
PAINT MONO (-790 4585);
FORCEPROP 0 LASTPIN (-800 4625) $PN 101
J 0
(-790 4635);
DISPLAY 0.680851 (-790 4635);
PAINT MONO (-790 4635);
FORCEPROP 0 LASTPIN (-800 4675) $PN 103
J 0
(-790 4685);
DISPLAY 0.680851 (-790 4685);
PAINT MONO (-790 4685);
FORCEPROP 0 LASTPIN (-800 4725) $PN 106
J 0
(-790 4735);
DISPLAY 0.680851 (-790 4735);
PAINT MONO (-790 4735);
FORCEPROP 0 LASTPIN (-800 4775) $PN 108
J 0
(-790 4785);
DISPLAY 0.680851 (-790 4785);
PAINT MONO (-790 4785);
FORCEPROP 0 LASTPIN (-800 4825) $PN 110
J 0
(-790 4835);
DISPLAY 0.680851 (-790 4835);
PAINT MONO (-790 4835);
FORCEPROP 0 LASTPIN (-800 4875) $PN 112
J 0
(-790 4885);
DISPLAY 0.680851 (-790 4885);
PAINT MONO (-790 4885);
FORCEPROP 0 LASTPIN (-800 4925) $PN 114
J 0
(-790 4935);
DISPLAY 0.680851 (-790 4935);
PAINT MONO (-790 4935);
FORCEPROP 0 LASTPIN (-800 4975) $PN 117
J 0
(-790 4985);
DISPLAY 0.680851 (-790 4985);
PAINT MONO (-790 4985);
FORCEPROP 0 LASTPIN (-800 5025) $PN 119
J 0
(-790 5035);
DISPLAY 0.680851 (-790 5035);
PAINT MONO (-790 5035);
FORCEPROP 0 LASTPIN (-800 5075) $PN 121
J 0
(-790 5085);
DISPLAY 0.680851 (-790 5085);
PAINT MONO (-790 5085);
FORCEPROP 0 LASTPIN (-800 5125) $PN 123
J 0
(-790 5135);
DISPLAY 0.680851 (-790 5135);
PAINT MONO (-790 5135);
FORCEPROP 0 LASTPIN (-800 5175) $PN 125
J 0
(-790 5185);
DISPLAY 0.680851 (-790 5185);
PAINT MONO (-790 5185);
FORCEPROP 0 LASTPIN (-800 5225) $PN 128
J 0
(-790 5235);
DISPLAY 0.680851 (-790 5235);
PAINT MONO (-790 5235);
FORCEPROP 0 LASTPIN (-800 5275) $PN 130
J 0
(-790 5285);
DISPLAY 0.680851 (-790 5285);
PAINT MONO (-790 5285);
FORCEPROP 0 LASTPIN (-800 5325) $PN 132
J 0
(-790 5335);
DISPLAY 0.680851 (-790 5335);
PAINT MONO (-790 5335);
FORCEPROP 0 LASTPIN (-800 5375) $PN 134
J 0
(-790 5385);
DISPLAY 0.680851 (-790 5385);
PAINT MONO (-790 5385);
FORCEPROP 0 LASTPIN (-800 5425) $PN 136
J 0
(-790 5435);
DISPLAY 0.680851 (-790 5435);
PAINT MONO (-790 5435);
FORCEPROP 0 LASTPIN (-800 5475) $PN 139
J 0
(-790 5485);
DISPLAY 0.680851 (-790 5485);
PAINT MONO (-790 5485);
FORCEPROP 0 LASTPIN (-800 5525) $PN 141
J 0
(-790 5535);
DISPLAY 0.680851 (-790 5535);
PAINT MONO (-790 5535);
FORCEPROP 0 LASTPIN (-800 5575) $PN 143
J 0
(-790 5585);
DISPLAY 0.680851 (-790 5585);
PAINT MONO (-790 5585);
FORCEPROP 0 LASTPIN (-2000 2325) $PN 151
J 2
(-2010 2335);
DISPLAY 0.680851 (-2010 2335);
PAINT MONO (-2010 2335);
FORCEPROP 0 LASTPIN (-2000 2375) $PN 153
J 2
(-2010 2385);
DISPLAY 0.680851 (-2010 2385);
PAINT MONO (-2010 2385);
FORCEPROP 0 LASTPIN (-2000 2425) $PN 155
J 2
(-2010 2435);
DISPLAY 0.680851 (-2010 2435);
PAINT MONO (-2010 2435);
FORCEPROP 0 LASTPIN (-2000 2475) $PN 158
J 2
(-2010 2485);
DISPLAY 0.680851 (-2010 2485);
PAINT MONO (-2010 2485);
FORCEPROP 0 LASTPIN (-2000 2525) $PN 160
J 2
(-2010 2535);
DISPLAY 0.680851 (-2010 2535);
PAINT MONO (-2010 2535);
FORCEPROP 0 LASTPIN (-2000 2575) $PN 162
J 2
(-2010 2585);
DISPLAY 0.680851 (-2010 2585);
PAINT MONO (-2010 2585);
FORCEPROP 0 LASTPIN (-2000 2625) $PN 164
J 2
(-2010 2635);
DISPLAY 0.680851 (-2010 2635);
PAINT MONO (-2010 2635);
FORCEPROP 0 LASTPIN (-2000 2675) $PN 166
J 2
(-2010 2685);
DISPLAY 0.680851 (-2010 2685);
PAINT MONO (-2010 2685);
FORCEPROP 0 LASTPIN (-2000 2725) $PN 169
J 2
(-2010 2735);
DISPLAY 0.680851 (-2010 2735);
PAINT MONO (-2010 2735);
FORCEPROP 0 LASTPIN (-2000 2775) $PN 171
J 2
(-2010 2785);
DISPLAY 0.680851 (-2010 2785);
PAINT MONO (-2010 2785);
FORCEPROP 0 LASTPIN (-2000 2825) $PN 173
J 2
(-2010 2835);
DISPLAY 0.680851 (-2010 2835);
PAINT MONO (-2010 2835);
FORCEPROP 0 LASTPIN (-2000 2875) $PN 175
J 2
(-2010 2885);
DISPLAY 0.680851 (-2010 2885);
PAINT MONO (-2010 2885);
FORCEPROP 0 LASTPIN (-2000 2925) $PN 177
J 2
(-2010 2935);
DISPLAY 0.680851 (-2010 2935);
PAINT MONO (-2010 2935);
FORCEPROP 0 LASTPIN (-2000 2975) $PN 180
J 2
(-2010 2985);
DISPLAY 0.680851 (-2010 2985);
PAINT MONO (-2010 2985);
FORCEPROP 0 LASTPIN (-2000 3025) $PN 182
J 2
(-2010 3035);
DISPLAY 0.680851 (-2010 3035);
PAINT MONO (-2010 3035);
FORCEPROP 0 LASTPIN (-2000 3075) $PN 184
J 2
(-2010 3085);
DISPLAY 0.680851 (-2010 3085);
PAINT MONO (-2010 3085);
FORCEPROP 0 LASTPIN (-2000 3125) $PN 186
J 2
(-2010 3135);
DISPLAY 0.680851 (-2010 3135);
PAINT MONO (-2010 3135);
FORCEPROP 0 LASTPIN (-2000 3175) $PN 188
J 2
(-2010 3185);
DISPLAY 0.680851 (-2010 3185);
PAINT MONO (-2010 3185);
FORCEPROP 0 LASTPIN (-2000 3225) $PN 191
J 2
(-2010 3235);
DISPLAY 0.680851 (-2010 3235);
PAINT MONO (-2010 3235);
FORCEPROP 0 LASTPIN (-2000 3275) $PN 193
J 2
(-2010 3285);
DISPLAY 0.680851 (-2010 3285);
PAINT MONO (-2010 3285);
FORCEPROP 0 LASTPIN (-2000 3325) $PN 195
J 2
(-2010 3335);
DISPLAY 0.680851 (-2010 3335);
PAINT MONO (-2010 3335);
FORCEPROP 0 LASTPIN (-2000 3375) $PN 197
J 2
(-2010 3385);
DISPLAY 0.680851 (-2010 3385);
PAINT MONO (-2010 3385);
FORCEPROP 0 LASTPIN (-2000 3425) $PN 199
J 2
(-2010 3435);
DISPLAY 0.680851 (-2010 3435);
PAINT MONO (-2010 3435);
FORCEPROP 0 LASTPIN (-2000 3475) $PN 202
J 2
(-2010 3485);
DISPLAY 0.680851 (-2010 3485);
PAINT MONO (-2010 3485);
FORCEPROP 0 LASTPIN (-2000 3525) $PN 204
J 2
(-2010 3535);
DISPLAY 0.680851 (-2010 3535);
PAINT MONO (-2010 3535);
FORCEPROP 0 LASTPIN (-2000 3575) $PN 206
J 2
(-2010 3585);
DISPLAY 0.680851 (-2010 3585);
PAINT MONO (-2010 3585);
FORCEPROP 0 LASTPIN (-2000 3625) $PN 208
J 2
(-2010 3635);
DISPLAY 0.680851 (-2010 3635);
PAINT MONO (-2010 3635);
FORCEPROP 0 LASTPIN (-2000 3675) $PN 210
J 2
(-2010 3685);
DISPLAY 0.680851 (-2010 3685);
PAINT MONO (-2010 3685);
FORCEPROP 0 LASTPIN (-2000 3725) $PN 212
J 2
(-2010 3735);
DISPLAY 0.680851 (-2010 3735);
PAINT MONO (-2010 3735);
FORCEPROP 0 LASTPIN (-2000 3775) $PN 214
J 2
(-2010 3785);
DISPLAY 0.680851 (-2010 3785);
PAINT MONO (-2010 3785);
FORCEPROP 0 LASTPIN (-2000 3825) $PN 216
J 2
(-2010 3835);
DISPLAY 0.680851 (-2010 3835);
PAINT MONO (-2010 3835);
FORCEPROP 0 LASTPIN (-2000 3875) $PN 219
J 2
(-2010 3885);
DISPLAY 0.680851 (-2010 3885);
PAINT MONO (-2010 3885);
FORCEPROP 0 LASTPIN (-2000 3925) $PN 222
J 2
(-2010 3935);
DISPLAY 0.680851 (-2010 3935);
PAINT MONO (-2010 3935);
FORCEPROP 0 LASTPIN (-2000 3975) $PN 224
J 2
(-2010 3985);
DISPLAY 0.680851 (-2010 3985);
PAINT MONO (-2010 3985);
FORCEPROP 0 LASTPIN (-2000 4025) $PN 226
J 2
(-2010 4035);
DISPLAY 0.680851 (-2010 4035);
PAINT MONO (-2010 4035);
FORCEPROP 0 LASTPIN (-2000 4075) $PN 228
J 2
(-2010 4085);
DISPLAY 0.680851 (-2010 4085);
PAINT MONO (-2010 4085);
FORCEPROP 0 LASTPIN (-2000 4125) $PN 230
J 2
(-2010 4135);
DISPLAY 0.680851 (-2010 4135);
PAINT MONO (-2010 4135);
FORCEPROP 0 LASTPIN (-2000 4175) $PN 233
J 2
(-2010 4185);
DISPLAY 0.680851 (-2010 4185);
PAINT MONO (-2010 4185);
FORCEPROP 0 LASTPIN (-2000 4225) $PN 235
J 2
(-2010 4235);
DISPLAY 0.680851 (-2010 4235);
PAINT MONO (-2010 4235);
FORCEPROP 0 LASTPIN (-2000 4275) $PN 237
J 2
(-2010 4285);
DISPLAY 0.680851 (-2010 4285);
PAINT MONO (-2010 4285);
FORCEPROP 0 LASTPIN (-2000 4325) $PN 240
J 2
(-2010 4335);
DISPLAY 0.680851 (-2010 4335);
PAINT MONO (-2010 4335);
FORCEPROP 0 LASTPIN (-2000 4375) $PN 242
J 2
(-2010 4385);
DISPLAY 0.680851 (-2010 4385);
PAINT MONO (-2010 4385);
FORCEPROP 0 LASTPIN (-2000 4425) $PN 244
J 2
(-2010 4435);
DISPLAY 0.680851 (-2010 4435);
PAINT MONO (-2010 4435);
FORCEPROP 0 LASTPIN (-2000 4475) $PN 246
J 2
(-2010 4485);
DISPLAY 0.680851 (-2010 4485);
PAINT MONO (-2010 4485);
FORCEPROP 0 LASTPIN (-2000 4525) $PN 248
J 2
(-2010 4535);
DISPLAY 0.680851 (-2010 4535);
PAINT MONO (-2010 4535);
FORCEPROP 0 LASTPIN (-2000 4575) $PN 251
J 2
(-2010 4585);
DISPLAY 0.680851 (-2010 4585);
PAINT MONO (-2010 4585);
FORCEPROP 0 LASTPIN (-2000 4625) $PN 253
J 2
(-2010 4635);
DISPLAY 0.680851 (-2010 4635);
PAINT MONO (-2010 4635);
FORCEPROP 0 LASTPIN (-2000 4675) $PN 255
J 2
(-2010 4685);
DISPLAY 0.680851 (-2010 4685);
PAINT MONO (-2010 4685);
FORCEPROP 0 LASTPIN (-2000 4725) $PN 257
J 2
(-2010 4735);
DISPLAY 0.680851 (-2010 4735);
PAINT MONO (-2010 4735);
FORCEPROP 0 LASTPIN (-2000 4775) $PN 259
J 2
(-2010 4785);
DISPLAY 0.680851 (-2010 4785);
PAINT MONO (-2010 4785);
FORCEPROP 0 LASTPIN (-2000 4825) $PN 262
J 2
(-2010 4835);
DISPLAY 0.680851 (-2010 4835);
PAINT MONO (-2010 4835);
FORCEPROP 0 LASTPIN (-2000 4875) $PN 264
J 2
(-2010 4885);
DISPLAY 0.680851 (-2010 4885);
PAINT MONO (-2010 4885);
FORCEPROP 0 LASTPIN (-2000 4925) $PN 266
J 2
(-2010 4935);
DISPLAY 0.680851 (-2010 4935);
PAINT MONO (-2010 4935);
FORCEPROP 0 LASTPIN (-2000 4975) $PN 268
J 2
(-2010 4985);
DISPLAY 0.680851 (-2010 4985);
PAINT MONO (-2010 4985);
FORCEPROP 0 LASTPIN (-2000 5025) $PN 270
J 2
(-2010 5035);
DISPLAY 0.680851 (-2010 5035);
PAINT MONO (-2010 5035);
FORCEPROP 0 LASTPIN (-2000 5075) $PN 273
J 2
(-2010 5085);
DISPLAY 0.680851 (-2010 5085);
PAINT MONO (-2010 5085);
FORCEPROP 0 LASTPIN (-2000 5125) $PN 275
J 2
(-2010 5135);
DISPLAY 0.680851 (-2010 5135);
PAINT MONO (-2010 5135);
FORCEPROP 0 LASTPIN (-2000 5175) $PN 277
J 2
(-2010 5185);
DISPLAY 0.680851 (-2010 5185);
PAINT MONO (-2010 5185);
FORCEPROP 0 LASTPIN (-2000 5225) $PN 279
J 2
(-2010 5235);
DISPLAY 0.680851 (-2010 5235);
PAINT MONO (-2010 5235);
FORCEPROP 0 LASTPIN (-2000 5275) $PN 281
J 2
(-2010 5285);
DISPLAY 0.680851 (-2010 5285);
PAINT MONO (-2010 5285);
FORCEPROP 0 LASTPIN (-2000 5325) $PN 284
J 2
(-2010 5335);
DISPLAY 0.680851 (-2010 5335);
PAINT MONO (-2010 5335);
FORCEPROP 0 LASTPIN (-2000 5375) $PN 286
J 2
(-2010 5385);
DISPLAY 0.680851 (-2010 5385);
PAINT MONO (-2010 5385);
FORCEPROP 0 LASTPIN (-2000 5425) $PN 288
J 2
(-2010 5435);
DISPLAY 0.680851 (-2010 5435);
PAINT MONO (-2010 5435);
FORCEPROP 2 LAST PART_TYPE SMLF
J 0
(-1850 6000);
DISPLAY 1.021277 (-1850 6000);
FORCEPROP 2 LAST VALUE SCONN288_DDR506112002KQ
J 0
(-1850 5950);
DISPLAY 0.489362 (-1850 5950);
PAINT SKYBLUE (-1850 5950);
FORCEPROP 1 LAST MATERIAL IO
J 0
(-1850 5750);
DISPLAY 0.468085 (-1850 5750);
PAINT SKYBLUE (-1850 5750);
FORCEPROP 1 LAST CDS_LMAN_SYM_OUTLINE -450,1800,450,-1750
J 0
(-1400 3925);
DISPLAY 0.468085 (-1400 3925);
PAINT GREEN (-1400 3925);
DISPLAY INVISIBLE (-1400 3925);
FORCEPROP 1 LAST NEEDS_NO_SIZE TRUE
J 0
(-1400 3925);
DISPLAY 0.723404 (-1400 3925);
PAINT GREEN (-1400 3925);
DISPLAY INVISIBLE (-1400 3925);
FORCEPROP 2 LAST CDS_LIB pure_quanta
J 0
(-1400 3925);
DISPLAY INVISIBLE (-1400 3925);
FORCEPROP 1 LAST PATH I350
J 0
(-1400 3925);
DISPLAY 0.723404 (-1400 3925);
PAINT GREEN (-1400 3925);
DISPLAY INVISIBLE (-1400 3925);
FORCEPROP 1 LAST PART_NUMBER DFHST8FS479
J 0
(-1850 5825);
DISPLAY 0.468085 (-1850 5825);
PAINT SKYBLUE (-1850 5825);
DISPLAY INVISIBLE (-1850 5825);
FORCEADD OFFPAGE..5
(-8425 3225);
FORCEPROP 2 LAST $XR0 14 
J 0
(-8649 3225);
DISPLAY 0.638298 (-8649 3225);
PAINT MONO (-8649 3225);
FORCEPROP 2 LAST CDS_LIB mstr_standard
J 0
(-8425 3225);
DISPLAY INVISIBLE (-8425 3225);
FORCEPROP 1 LAST OFFPAGE TRUE
J 0
(-8100 3100);
DISPLAY 0.872340 (-8100 3100);
PAINT GREEN (-8100 3100);
DISPLAY INVISIBLE (-8100 3100);
FORCEPROP 1 LAST COMMENT_BODY TRUE
J 0
(-8325 3150);
DISPLAY 0.872340 (-8325 3150);
PAINT GREEN (-8325 3150);
DISPLAY INVISIBLE (-8325 3150);
FORCEPROP 2 LAST PATH I351
J 0
(-8375 3300);
DISPLAY 1.021277 (-8375 3300);
DISPLAY INVISIBLE (-8375 3300);
FORCEADD GND..1
(-8875 3175);
FORCEPROP 3 LASTPIN (-8875 3225) SIG_NAME GND\g
J 0
(-8865 3235);
DISPLAY 0.659574 (-8865 3235);
PAINT MONO (-8865 3235);
DISPLAY INVISIBLE (-8865 3235);
FORCEPROP 2 LAST BOM_COST MEM
J 0
(-8850 3300);
DISPLAY 0.659574 (-8850 3300);
DISPLAY INVISIBLE (-8850 3300);
FORCEPROP 1 LAST SIZE 1B
J 0
(-8800 3125);
DISPLAY 0.723404 (-8800 3125);
PAINT GREEN (-8800 3125);
DISPLAY INVISIBLE (-8800 3125);
FORCEPROP 2 LAST CDS_LIB mstr_symbols
J 0
(-8875 3175);
DISPLAY 0.808511 (-8875 3175);
DISPLAY INVISIBLE (-8875 3175);
FORCEPROP 1 LAST VOLTAGE 0
J 0
(-8895 3270);
DISPLAY 0.829787 (-8895 3270);
PAINT SKYBLUE (-8895 3270);
DISPLAY INVISIBLE (-8895 3270);
FORCEPROP 2 LAST ROOM MEM_EFGH_DECOUPLING_CAPS
J 0
(-8850 3250);
DISPLAY 0.659574 (-8850 3250);
PAINT RED (-8850 3250);
DISPLAY INVISIBLE (-8850 3250);
FORCEPROP 1 LAST BODY_TYPE PLUMBING
J 0
(-8920 3132);
DISPLAY 0.276596 (-8920 3132);
PAINT GREEN (-8920 3132);
DISPLAY INVISIBLE (-8920 3132);
FORCEPROP 1 LAST HDL_POWER GND
J 0
(-8875 3325);
DISPLAY 0.723404 (-8875 3325);
PAINT GREEN (-8875 3325);
DISPLAY INVISIBLE (-8875 3325);
FORCEPROP 1 LAST PATH I359
J 0
(-8800 3175);
DISPLAY 0.872340 (-8800 3175);
PAINT AQUA (-8800 3175);
DISPLAY INVISIBLE (-8800 3175);
FORCEADD Q_CAP..1
R 2
(-8875 3400);
FORCEPROP 1 LAST LOCATION C104
J 2
(-8925 3500);
DISPLAY 0.489362 (-8925 3500);
PAINT SKYBLUE (-8925 3500);
FORCEPROP 0 LAST $SEC 1
J 0
(-8925 3550);
DISPLAY 0.680851 (-8925 3550);
PAINT MONO (-8925 3550);
DISPLAY INVISIBLE (-8925 3550);
FORCEPROP 0 LAST CDS_SEC 1
J 0
(-8925 3550);
DISPLAY 1.021277 (-8925 3550);
DISPLAY INVISIBLE (-8925 3550);
FORCEPROP 1 LASTPIN (-8875 3500) $PN 1
J 2
(-8885 3480);
DISPLAY 0.489362 (-8885 3480);
PAINT MONO (-8885 3480);
FORCEPROP 1 LASTPIN (-8875 3300) $PN 2
J 2
(-8885 3280);
DISPLAY 0.489362 (-8885 3280);
PAINT MONO (-8885 3280);
FORCEPROP 1 LAST MATERIAL X7R
J 2
(-8925 3300);
DISPLAY 0.489362 (-8925 3300);
PAINT SKYBLUE (-8925 3300);
FORCEPROP 1 LAST TOLERANCE 10%
J 2
(-8925 3350);
DISPLAY 0.489362 (-8925 3350);
PAINT SKYBLUE (-8925 3350);
FORCEPROP 1 LAST VOLTAGE 25V
J 2
(-8925 3400);
DISPLAY 0.489362 (-8925 3400);
PAINT SKYBLUE (-8925 3400);
FORCEPROP 1 LAST PACK_TYPE 0402
J 2
(-8925 3200);
DISPLAY 0.489362 (-8925 3200);
PAINT SKYBLUE (-8925 3200);
FORCEPROP 1 LAST VALUE 0.1UF
J 2
(-8925 3450);
DISPLAY 0.489362 (-8925 3450);
PAINT SKYBLUE (-8925 3450);
FORCEPROP 2 LAST CDS_LIB pure_quanta
J 0
(-8875 3400);
DISPLAY INVISIBLE (-8875 3400);
FORCEPROP 0 LAST BOM_COST MEM
J 2
(-8930 3545);
DISPLAY 0.595745 (-8930 3545);
PAINT MONO (-8930 3545);
DISPLAY INVISIBLE (-8930 3545);
FORCEPROP 2 LAST ROOM 
J 2
(-8930 3545);
DISPLAY 0.595745 (-8930 3545);
PAINT RED (-8930 3545);
DISPLAY INVISIBLE (-8930 3545);
FORCEPROP 1 LAST PATH I360
J 2
(-8925 3550);
DISPLAY 0.978723 (-8925 3550);
PAINT WHITE (-8925 3550);
DISPLAY INVISIBLE (-8925 3550);
FORCEPROP 1 LAST PART_NUMBER CH4104K1B00
J 2
(-8925 3250);
DISPLAY 0.489362 (-8925 3250);
PAINT SKYBLUE (-8925 3250);
DISPLAY INVISIBLE (-8925 3250);
FORCEADD OFFPAGE..6
(-9225 2325);
FORCEPROP 2 LAST $XR4 91 
J 0
(-9534 2397);
DISPLAY 0.638298 (-9534 2397);
PAINT MONO (-9534 2397);
FORCEPROP 2 LAST $XR3 89 
J 0
(-9534 2253);
DISPLAY 0.638298 (-9534 2253);
PAINT MONO (-9534 2253);
FORCEPROP 2 LAST $XR2 88 
J 0
(-9534 2361);
DISPLAY 0.638298 (-9534 2361);
PAINT MONO (-9534 2361);
FORCEPROP 2 LAST $XR1 87 
J 0
(-9534 2289);
DISPLAY 0.638298 (-9534 2289);
PAINT MONO (-9534 2289);
FORCEPROP 2 LAST $XR0 86 
J 0
(-9534 2325);
DISPLAY 0.638298 (-9534 2325);
PAINT MONO (-9534 2325);
FORCEPROP 2 LAST CDS_LIB mstr_standard
J 0
(-9225 2325);
DISPLAY INVISIBLE (-9225 2325);
FORCEPROP 1 LAST OFFPAGE TRUE
J 0
(-8900 2200);
DISPLAY 0.872340 (-8900 2200);
PAINT GREEN (-8900 2200);
DISPLAY INVISIBLE (-8900 2200);
FORCEPROP 1 LAST COMMENT_BODY TRUE
J 0
(-9125 2250);
DISPLAY 0.872340 (-9125 2250);
PAINT GREEN (-9125 2250);
DISPLAY INVISIBLE (-9125 2250);
FORCEPROP 2 LAST PATH I361
J 0
(-9175 2400);
DISPLAY 1.021277 (-9175 2400);
DISPLAY INVISIBLE (-9175 2400);
FORCEADD Q_RES..1
R 2
(-8725 2325);
FORCEPROP 1 LAST LOCATION R295
J 2
(-8675 2375);
DISPLAY 0.489362 (-8675 2375);
PAINT SKYBLUE (-8675 2375);
FORCEPROP 0 LAST $SEC 1
J 0
(-8675 2425);
DISPLAY 0.680851 (-8675 2425);
PAINT MONO (-8675 2425);
DISPLAY INVISIBLE (-8675 2425);
FORCEPROP 0 LAST CDS_SEC 1
J 0
(-8675 2425);
DISPLAY 1.021277 (-8675 2425);
DISPLAY INVISIBLE (-8675 2425);
FORCEPROP 1 LASTPIN (-8625 2325) $PN 1
J 2
(-8637 2337);
DISPLAY 0.489362 (-8637 2337);
PAINT MONO (-8637 2337);
FORCEPROP 1 LASTPIN (-8825 2325) $PN 2
J 2
(-8787 2337);
DISPLAY 0.489362 (-8787 2337);
PAINT MONO (-8787 2337);
FORCEPROP 1 LAST VALUE 1K
J 0
(-8725 2275);
DISPLAY 0.489362 (-8725 2275);
PAINT SKYBLUE (-8725 2275);
FORCEPROP 1 LAST TOLERANCE 1%
J 2
(-8600 2300);
DISPLAY 0.489362 (-8600 2300);
PAINT SKYBLUE (-8600 2300);
DISPLAY INVISIBLE (-8600 2300);
FORCEPROP 2 LAST CDS_LIB pure_quanta
J 0
(-8725 2325);
DISPLAY INVISIBLE (-8725 2325);
FORCEPROP 2 LAST BOM_COST MEM
J 0
(-8750 2475);
DISPLAY 0.744681 (-8750 2475);
PAINT WHITE (-8750 2475);
DISPLAY INVISIBLE (-8750 2475);
FORCEPROP 1 LAST WATTAGE 1/16W
J 0
(-8650 2250);
DISPLAY 0.489362 (-8650 2250);
PAINT SKYBLUE (-8650 2250);
DISPLAY INVISIBLE (-8650 2250);
FORCEPROP 1 LAST MATERIAL CHIP
J 0
(-8900 2300);
DISPLAY 0.489362 (-8900 2300);
PAINT SKYBLUE (-8900 2300);
DISPLAY INVISIBLE (-8900 2300);
FORCEPROP 1 LAST PACK_TYPE 0402LF
J 0
(-8900 2250);
DISPLAY 0.489362 (-8900 2250);
PAINT SKYBLUE (-8900 2250);
DISPLAY INVISIBLE (-8900 2250);
FORCEPROP 2 LAST ROOM 
J 0
(-8750 2425);
DISPLAY 0.744681 (-8750 2425);
PAINT RED (-8750 2425);
DISPLAY INVISIBLE (-8750 2425);
FORCEPROP 1 LAST PATH I362
J 2
(-8675 2475);
DISPLAY 0.978723 (-8675 2475);
PAINT WHITE (-8675 2475);
DISPLAY INVISIBLE (-8675 2475);
FORCEPROP 1 LAST PART_NUMBER CS21002FB06
J 0
(-8825 2375);
DISPLAY 0.489362 (-8825 2375);
PAINT SKYBLUE (-8825 2375);
DISPLAY INVISIBLE (-8825 2375);
FORCEADD VCC_CORE..1
(-8600 2650);
FORCEPROP 3 LASTPIN (-8600 2600) SIG_NAME P3V3\g
J 0
(-8590 2610);
DISPLAY 0.659574 (-8590 2610);
PAINT MONO (-8590 2610);
DISPLAY INVISIBLE (-8590 2610);
FORCEPROP 1 LAST HDL_POWER P3V3
J 1
(-8600 2700);
DISPLAY 0.489362 (-8600 2700);
PAINT GREEN (-8600 2700);
FORCEPROP 2 LAST CDS_LIB mstr_symbols
J 0
(-8600 2650);
DISPLAY INVISIBLE (-8600 2650);
FORCEPROP 0 LAST VOLTAGE 3.3
J 0
(-8875 2800);
DISPLAY 1.021277 (-8875 2800);
PAINT SKYBLUE (-8875 2800);
DISPLAY INVISIBLE (-8875 2800);
FORCEPROP 2 LAST ROOM PVCCINFAON_CPU0_CTRL
J 0
(-8600 2750);
DISPLAY 0.808511 (-8600 2750);
PAINT RED (-8600 2750);
DISPLAY INVISIBLE (-8600 2750);
FORCEPROP 1 LAST PATH I363
J 0
(-8550 2675);
DISPLAY 0.872340 (-8550 2675);
PAINT AQUA (-8550 2675);
DISPLAY INVISIBLE (-8550 2675);
FORCEADD Q_RES..2
(-8600 2475);
FORCEPROP 1 LAST LOCATION R93
J 0
(-8555 2600);
DISPLAY 0.489362 (-8555 2600);
PAINT SKYBLUE (-8555 2600);
FORCEPROP 0 LAST $SEC 1
J 0
(-8550 2650);
DISPLAY 0.680851 (-8550 2650);
PAINT MONO (-8550 2650);
DISPLAY INVISIBLE (-8550 2650);
FORCEPROP 0 LAST CDS_SEC 1
J 0
(-8550 2650);
DISPLAY 1.021277 (-8550 2650);
DISPLAY INVISIBLE (-8550 2650);
FORCEPROP 1 LASTPIN (-8600 2575) $PN 1
J 0
(-8595 2537);
DISPLAY 0.489362 (-8595 2537);
PAINT MONO (-8595 2537);
FORCEPROP 1 LASTPIN (-8600 2375) $PN 2
J 0
(-8595 2385);
DISPLAY 0.489362 (-8595 2385);
PAINT MONO (-8595 2385);
FORCEPROP 1 LAST WATTAGE 1/16W
J 0
(-8550 2500);
DISPLAY 0.489362 (-8550 2500);
PAINT SKYBLUE (-8550 2500);
FORCEPROP 1 LAST TOLERANCE 1%
J 0
(-8550 2525);
DISPLAY 0.489362 (-8550 2525);
PAINT SKYBLUE (-8550 2525);
FORCEPROP 1 LAST MATERIAL EMPTY
J 0
(-8550 2475);
DISPLAY 0.489362 (-8550 2475);
PAINT RED (-8550 2475);
FORCEPROP 1 LAST VALUE 1K
J 0
(-8555 2550);
DISPLAY 0.489362 (-8555 2550);
PAINT SKYBLUE (-8555 2550);
FORCEPROP 1 LAST PACK_TYPE 0402LF
J 0
(-8550 2425);
DISPLAY 0.489362 (-8550 2425);
PAINT SKYBLUE (-8550 2425);
FORCEPROP 2 LAST CDS_LIB pure_quanta
J 0
(-8600 2475);
DISPLAY INVISIBLE (-8600 2475);
FORCEPROP 2 LAST BOM_COST MEM
J 0
(-8550 2650);
DISPLAY 0.808511 (-8550 2650);
DISPLAY INVISIBLE (-8550 2650);
FORCEPROP 2 LAST ROOM 
J 0
(-8550 2700);
DISPLAY 0.808511 (-8550 2700);
PAINT RED (-8550 2700);
DISPLAY INVISIBLE (-8550 2700);
FORCEPROP 1 LAST PATH I364
J 0
(-8550 2650);
DISPLAY 0.978723 (-8550 2650);
PAINT WHITE (-8550 2650);
DISPLAY INVISIBLE (-8550 2650);
FORCEPROP 1 LAST PART_NUMBER CS21002FB06
J 0
(-8550 2450);
DISPLAY 0.489362 (-8550 2450);
PAINT SKYBLUE (-8550 2450);
DISPLAY INVISIBLE (-8550 2450);
FORCEADD OFFPAGE..2
(-2675 4725);
FORCEPROP 2 LAST $XR0 14 
J 0
(-2486 4725);
DISPLAY 0.638298 (-2486 4725);
PAINT MONO (-2486 4725);
FORCEPROP 2 LAST CDS_LIB mstr_standard
J 0
(-2675 4725);
DISPLAY 0.723404 (-2675 4725);
PAINT MONO (-2675 4725);
DISPLAY INVISIBLE (-2675 4725);
FORCEPROP 1 LAST OFFPAGE TRUE
J 0
(-2350 4600);
DISPLAY 0.723404 (-2350 4600);
PAINT GREEN (-2350 4600);
DISPLAY INVISIBLE (-2350 4600);
FORCEPROP 1 LAST COMMENT_BODY TRUE
J 0
(-2720 4630);
DISPLAY 0.872340 (-2720 4630);
PAINT GREEN (-2720 4630);
DISPLAY INVISIBLE (-2720 4630);
FORCEPROP 2 LAST PATH I366
J 0
(-2475 4775);
DISPLAY 0.680851 (-2475 4775);
DISPLAY INVISIBLE (-2475 4775);
FORCEADD OFFPAGE..2
(-2675 4675);
FORCEPROP 2 LAST $XR0 14 
J 0
(-2486 4675);
DISPLAY 0.638298 (-2486 4675);
PAINT MONO (-2486 4675);
FORCEPROP 2 LAST CDS_LIB mstr_standard
J 0
(-2675 4675);
DISPLAY 0.723404 (-2675 4675);
PAINT MONO (-2675 4675);
DISPLAY INVISIBLE (-2675 4675);
FORCEPROP 1 LAST OFFPAGE TRUE
J 0
(-2350 4550);
DISPLAY 0.723404 (-2350 4550);
PAINT GREEN (-2350 4550);
DISPLAY INVISIBLE (-2350 4550);
FORCEPROP 1 LAST COMMENT_BODY TRUE
J 0
(-2720 4580);
DISPLAY 0.872340 (-2720 4580);
PAINT GREEN (-2720 4580);
DISPLAY INVISIBLE (-2720 4580);
FORCEPROP 2 LAST PATH I367
J 0
(-2475 4725);
DISPLAY 0.680851 (-2475 4725);
DISPLAY INVISIBLE (-2475 4725);
FORCEADD TAP..1
(-3475 4625);
FORCEPROP 3 LASTPIN (-3525 4625) SIG_NAME M_E_CPU0_SA_DQS_DN<9>
J 0
(-3515 4635);
DISPLAY 0.659574 (-3515 4635);
PAINT MONO (-3515 4635);
DISPLAY INVISIBLE (-3515 4635);
FORCEPROP 1 LASTPIN (-3525 4625) BN 9
J 0
(-3537 4633);
DISPLAY 0.489362 (-3537 4633);
PAINT GREEN (-3537 4633);
FORCEPROP 2 LAST CDS_LIB mstr_standard
J 0
(-3475 4625);
DISPLAY 0.723404 (-3475 4625);
PAINT MONO (-3475 4625);
DISPLAY INVISIBLE (-3475 4625);
FORCEPROP 1 LAST BODY_TYPE PLUMBING
J 0
(-3475 4675);
DISPLAY 0.872340 (-3475 4675);
PAINT GREEN (-3475 4675);
DISPLAY INVISIBLE (-3475 4675);
FORCEPROP 1 LAST HDL_TAP TRUE
J 0
(-3150 4500);
DISPLAY 0.872340 (-3150 4500);
DISPLAY INVISIBLE (-3150 4500);
FORCEPROP 1 LAST PATH I368
J 0
(-3477 4625);
DISPLAY 0.872340 (-3477 4625);
PAINT GREEN (-3477 4625);
DISPLAY INVISIBLE (-3477 4625);
FORCEADD TAP..1
(-3675 4575);
FORCEPROP 3 LASTPIN (-3725 4575) SIG_NAME M_E_CPU0_SA_DQS_DP<8>
J 0
(-3715 4585);
DISPLAY 0.659574 (-3715 4585);
PAINT MONO (-3715 4585);
DISPLAY INVISIBLE (-3715 4585);
FORCEPROP 1 LASTPIN (-3725 4575) BN 8
J 0
(-3737 4583);
DISPLAY 0.489362 (-3737 4583);
PAINT GREEN (-3737 4583);
FORCEPROP 2 LAST CDS_LIB mstr_standard
J 0
(-3675 4575);
DISPLAY 0.723404 (-3675 4575);
PAINT MONO (-3675 4575);
DISPLAY INVISIBLE (-3675 4575);
FORCEPROP 1 LAST BODY_TYPE PLUMBING
J 0
(-3675 4625);
DISPLAY 0.872340 (-3675 4625);
PAINT GREEN (-3675 4625);
DISPLAY INVISIBLE (-3675 4625);
FORCEPROP 1 LAST HDL_TAP TRUE
J 0
(-3350 4450);
DISPLAY 0.872340 (-3350 4450);
DISPLAY INVISIBLE (-3350 4450);
FORCEPROP 1 LAST PATH I369
J 0
(-3677 4575);
DISPLAY 0.872340 (-3677 4575);
PAINT GREEN (-3677 4575);
DISPLAY INVISIBLE (-3677 4575);
FORCEADD TAP..1
(-3675 4675);
FORCEPROP 3 LASTPIN (-3725 4675) SIG_NAME M_E_CPU0_SA_DQS_DP<9>
J 0
(-3715 4685);
DISPLAY 0.659574 (-3715 4685);
PAINT MONO (-3715 4685);
DISPLAY INVISIBLE (-3715 4685);
FORCEPROP 1 LASTPIN (-3725 4675) BN 9
J 0
(-3737 4683);
DISPLAY 0.489362 (-3737 4683);
PAINT GREEN (-3737 4683);
FORCEPROP 2 LAST CDS_LIB mstr_standard
J 0
(-3675 4675);
DISPLAY 0.723404 (-3675 4675);
PAINT MONO (-3675 4675);
DISPLAY INVISIBLE (-3675 4675);
FORCEPROP 1 LAST BODY_TYPE PLUMBING
J 0
(-3675 4725);
DISPLAY 0.872340 (-3675 4725);
PAINT GREEN (-3675 4725);
DISPLAY INVISIBLE (-3675 4725);
FORCEPROP 1 LAST HDL_TAP TRUE
J 0
(-3350 4550);
DISPLAY 0.872340 (-3350 4550);
DISPLAY INVISIBLE (-3350 4550);
FORCEPROP 1 LAST PATH I370
J 0
(-3677 4675);
DISPLAY 0.872340 (-3677 4675);
PAINT GREEN (-3677 4675);
DISPLAY INVISIBLE (-3677 4675);
FORCEADD TAP..1
(-3475 4525);
FORCEPROP 3 LASTPIN (-3525 4525) SIG_NAME M_E_CPU0_SA_DQS_DN<8>
J 0
(-3515 4535);
DISPLAY 0.659574 (-3515 4535);
PAINT MONO (-3515 4535);
DISPLAY INVISIBLE (-3515 4535);
FORCEPROP 1 LASTPIN (-3525 4525) BN 8
J 0
(-3537 4533);
DISPLAY 0.489362 (-3537 4533);
PAINT GREEN (-3537 4533);
FORCEPROP 2 LAST CDS_LIB mstr_standard
J 0
(-3475 4525);
DISPLAY 0.723404 (-3475 4525);
PAINT MONO (-3475 4525);
DISPLAY INVISIBLE (-3475 4525);
FORCEPROP 1 LAST BODY_TYPE PLUMBING
J 0
(-3475 4575);
DISPLAY 0.872340 (-3475 4575);
PAINT GREEN (-3475 4575);
DISPLAY INVISIBLE (-3475 4575);
FORCEPROP 1 LAST HDL_TAP TRUE
J 0
(-3150 4400);
DISPLAY 0.872340 (-3150 4400);
DISPLAY INVISIBLE (-3150 4400);
FORCEPROP 1 LAST PATH I371
J 0
(-3477 4525);
DISPLAY 0.872340 (-3477 4525);
PAINT GREEN (-3477 4525);
DISPLAY INVISIBLE (-3477 4525);
FORCEADD TAP..1
(-3475 4325);
FORCEPROP 3 LASTPIN (-3525 4325) SIG_NAME M_E_CPU0_SA_DQS_DN<6>
J 0
(-3515 4335);
DISPLAY 0.659574 (-3515 4335);
PAINT MONO (-3515 4335);
DISPLAY INVISIBLE (-3515 4335);
FORCEPROP 1 LASTPIN (-3525 4325) BN 6
J 0
(-3537 4333);
DISPLAY 0.489362 (-3537 4333);
PAINT GREEN (-3537 4333);
FORCEPROP 2 LAST CDS_LIB mstr_standard
J 0
(-3475 4325);
DISPLAY 0.723404 (-3475 4325);
PAINT MONO (-3475 4325);
DISPLAY INVISIBLE (-3475 4325);
FORCEPROP 1 LAST BODY_TYPE PLUMBING
J 0
(-3475 4375);
DISPLAY 0.872340 (-3475 4375);
PAINT GREEN (-3475 4375);
DISPLAY INVISIBLE (-3475 4375);
FORCEPROP 1 LAST HDL_TAP TRUE
J 0
(-3150 4200);
DISPLAY 0.872340 (-3150 4200);
DISPLAY INVISIBLE (-3150 4200);
FORCEPROP 1 LAST PATH I372
J 0
(-3477 4325);
DISPLAY 0.872340 (-3477 4325);
PAINT GREEN (-3477 4325);
DISPLAY INVISIBLE (-3477 4325);
FORCEADD TAP..1
(-3475 4425);
FORCEPROP 3 LASTPIN (-3525 4425) SIG_NAME M_E_CPU0_SA_DQS_DN<7>
J 0
(-3515 4435);
DISPLAY 0.659574 (-3515 4435);
PAINT MONO (-3515 4435);
DISPLAY INVISIBLE (-3515 4435);
FORCEPROP 1 LASTPIN (-3525 4425) BN 7
J 0
(-3537 4433);
DISPLAY 0.489362 (-3537 4433);
PAINT GREEN (-3537 4433);
FORCEPROP 2 LAST CDS_LIB mstr_standard
J 0
(-3475 4425);
DISPLAY 0.723404 (-3475 4425);
PAINT MONO (-3475 4425);
DISPLAY INVISIBLE (-3475 4425);
FORCEPROP 1 LAST BODY_TYPE PLUMBING
J 0
(-3475 4475);
DISPLAY 0.872340 (-3475 4475);
PAINT GREEN (-3475 4475);
DISPLAY INVISIBLE (-3475 4475);
FORCEPROP 1 LAST HDL_TAP TRUE
J 0
(-3150 4300);
DISPLAY 0.872340 (-3150 4300);
DISPLAY INVISIBLE (-3150 4300);
FORCEPROP 1 LAST PATH I373
J 0
(-3477 4425);
DISPLAY 0.872340 (-3477 4425);
PAINT GREEN (-3477 4425);
DISPLAY INVISIBLE (-3477 4425);
FORCEADD TAP..1
(-3675 4475);
FORCEPROP 3 LASTPIN (-3725 4475) SIG_NAME M_E_CPU0_SA_DQS_DP<7>
J 0
(-3715 4485);
DISPLAY 0.659574 (-3715 4485);
PAINT MONO (-3715 4485);
DISPLAY INVISIBLE (-3715 4485);
FORCEPROP 1 LASTPIN (-3725 4475) BN 7
J 0
(-3737 4483);
DISPLAY 0.489362 (-3737 4483);
PAINT GREEN (-3737 4483);
FORCEPROP 2 LAST CDS_LIB mstr_standard
J 0
(-3675 4475);
DISPLAY 0.723404 (-3675 4475);
PAINT MONO (-3675 4475);
DISPLAY INVISIBLE (-3675 4475);
FORCEPROP 1 LAST BODY_TYPE PLUMBING
J 0
(-3675 4525);
DISPLAY 0.872340 (-3675 4525);
PAINT GREEN (-3675 4525);
DISPLAY INVISIBLE (-3675 4525);
FORCEPROP 1 LAST HDL_TAP TRUE
J 0
(-3350 4350);
DISPLAY 0.872340 (-3350 4350);
DISPLAY INVISIBLE (-3350 4350);
FORCEPROP 1 LAST PATH I374
J 0
(-3677 4475);
DISPLAY 0.872340 (-3677 4475);
PAINT GREEN (-3677 4475);
DISPLAY INVISIBLE (-3677 4475);
FORCEADD TAP..1
(-3675 4375);
FORCEPROP 3 LASTPIN (-3725 4375) SIG_NAME M_E_CPU0_SA_DQS_DP<6>
J 0
(-3715 4385);
DISPLAY 0.659574 (-3715 4385);
PAINT MONO (-3715 4385);
DISPLAY INVISIBLE (-3715 4385);
FORCEPROP 1 LASTPIN (-3725 4375) BN 6
J 0
(-3737 4383);
DISPLAY 0.489362 (-3737 4383);
PAINT GREEN (-3737 4383);
FORCEPROP 2 LAST CDS_LIB mstr_standard
J 0
(-3675 4375);
DISPLAY 0.723404 (-3675 4375);
PAINT MONO (-3675 4375);
DISPLAY INVISIBLE (-3675 4375);
FORCEPROP 1 LAST BODY_TYPE PLUMBING
J 0
(-3675 4425);
DISPLAY 0.872340 (-3675 4425);
PAINT GREEN (-3675 4425);
DISPLAY INVISIBLE (-3675 4425);
FORCEPROP 1 LAST HDL_TAP TRUE
J 0
(-3350 4250);
DISPLAY 0.872340 (-3350 4250);
DISPLAY INVISIBLE (-3350 4250);
FORCEPROP 1 LAST PATH I375
J 0
(-3677 4375);
DISPLAY 0.872340 (-3677 4375);
PAINT GREEN (-3677 4375);
DISPLAY INVISIBLE (-3677 4375);
FORCEADD OFFPAGE..2
(-2675 3625);
FORCEPROP 2 LAST $XR0 14 
J 0
(-2486 3625);
DISPLAY 0.638298 (-2486 3625);
PAINT MONO (-2486 3625);
FORCEPROP 2 LAST CDS_LIB mstr_standard
J 0
(-2675 3625);
DISPLAY 0.723404 (-2675 3625);
PAINT MONO (-2675 3625);
DISPLAY INVISIBLE (-2675 3625);
FORCEPROP 1 LAST OFFPAGE TRUE
J 0
(-2350 3500);
DISPLAY 0.723404 (-2350 3500);
PAINT GREEN (-2350 3500);
DISPLAY INVISIBLE (-2350 3500);
FORCEPROP 1 LAST COMMENT_BODY TRUE
J 0
(-2720 3530);
DISPLAY 0.872340 (-2720 3530);
PAINT GREEN (-2720 3530);
DISPLAY INVISIBLE (-2720 3530);
FORCEPROP 2 LAST PATH I376
J 0
(-2475 3675);
DISPLAY 0.680851 (-2475 3675);
DISPLAY INVISIBLE (-2475 3675);
FORCEADD OFFPAGE..2
(-2675 3675);
FORCEPROP 2 LAST $XR0 14 
J 0
(-2486 3675);
DISPLAY 0.638298 (-2486 3675);
PAINT MONO (-2486 3675);
FORCEPROP 2 LAST CDS_LIB mstr_standard
J 0
(-2675 3675);
DISPLAY 0.723404 (-2675 3675);
PAINT MONO (-2675 3675);
DISPLAY INVISIBLE (-2675 3675);
FORCEPROP 1 LAST OFFPAGE TRUE
J 0
(-2350 3550);
DISPLAY 0.723404 (-2350 3550);
PAINT GREEN (-2350 3550);
DISPLAY INVISIBLE (-2350 3550);
FORCEPROP 1 LAST COMMENT_BODY TRUE
J 0
(-2720 3580);
DISPLAY 0.872340 (-2720 3580);
PAINT GREEN (-2720 3580);
DISPLAY INVISIBLE (-2720 3580);
FORCEPROP 2 LAST PATH I377
J 0
(-2475 3725);
DISPLAY 0.680851 (-2475 3725);
DISPLAY INVISIBLE (-2475 3725);
FORCEADD TAP..1
(-3475 4125);
FORCEPROP 3 LASTPIN (-3525 4125) SIG_NAME M_E_CPU0_SA_DQS_DN<4>
J 0
(-3515 4135);
DISPLAY 0.659574 (-3515 4135);
PAINT MONO (-3515 4135);
DISPLAY INVISIBLE (-3515 4135);
FORCEPROP 1 LASTPIN (-3525 4125) BN 4
J 0
(-3537 4133);
DISPLAY 0.489362 (-3537 4133);
PAINT GREEN (-3537 4133);
FORCEPROP 2 LAST CDS_LIB mstr_standard
J 0
(-3475 4125);
DISPLAY 0.723404 (-3475 4125);
PAINT MONO (-3475 4125);
DISPLAY INVISIBLE (-3475 4125);
FORCEPROP 1 LAST BODY_TYPE PLUMBING
J 0
(-3475 4175);
DISPLAY 0.872340 (-3475 4175);
PAINT GREEN (-3475 4175);
DISPLAY INVISIBLE (-3475 4175);
FORCEPROP 1 LAST HDL_TAP TRUE
J 0
(-3150 4000);
DISPLAY 0.872340 (-3150 4000);
DISPLAY INVISIBLE (-3150 4000);
FORCEPROP 1 LAST PATH I378
J 0
(-3477 4125);
DISPLAY 0.872340 (-3477 4125);
PAINT GREEN (-3477 4125);
DISPLAY INVISIBLE (-3477 4125);
FORCEADD TAP..1
(-3475 4225);
FORCEPROP 3 LASTPIN (-3525 4225) SIG_NAME M_E_CPU0_SA_DQS_DN<5>
J 0
(-3515 4235);
DISPLAY 0.659574 (-3515 4235);
PAINT MONO (-3515 4235);
DISPLAY INVISIBLE (-3515 4235);
FORCEPROP 1 LASTPIN (-3525 4225) BN 5
J 0
(-3537 4233);
DISPLAY 0.489362 (-3537 4233);
PAINT GREEN (-3537 4233);
FORCEPROP 2 LAST CDS_LIB mstr_standard
J 0
(-3475 4225);
DISPLAY 0.723404 (-3475 4225);
PAINT MONO (-3475 4225);
DISPLAY INVISIBLE (-3475 4225);
FORCEPROP 1 LAST BODY_TYPE PLUMBING
J 0
(-3475 4275);
DISPLAY 0.872340 (-3475 4275);
PAINT GREEN (-3475 4275);
DISPLAY INVISIBLE (-3475 4275);
FORCEPROP 1 LAST HDL_TAP TRUE
J 0
(-3150 4100);
DISPLAY 0.872340 (-3150 4100);
DISPLAY INVISIBLE (-3150 4100);
FORCEPROP 1 LAST PATH I379
J 0
(-3477 4225);
DISPLAY 0.872340 (-3477 4225);
PAINT GREEN (-3477 4225);
DISPLAY INVISIBLE (-3477 4225);
FORCEADD TAP..1
(-3675 4175);
FORCEPROP 3 LASTPIN (-3725 4175) SIG_NAME M_E_CPU0_SA_DQS_DP<4>
J 0
(-3715 4185);
DISPLAY 0.659574 (-3715 4185);
PAINT MONO (-3715 4185);
DISPLAY INVISIBLE (-3715 4185);
FORCEPROP 1 LASTPIN (-3725 4175) BN 4
J 0
(-3737 4183);
DISPLAY 0.489362 (-3737 4183);
PAINT GREEN (-3737 4183);
FORCEPROP 2 LAST CDS_LIB mstr_standard
J 0
(-3675 4175);
DISPLAY 0.723404 (-3675 4175);
PAINT MONO (-3675 4175);
DISPLAY INVISIBLE (-3675 4175);
FORCEPROP 1 LAST BODY_TYPE PLUMBING
J 0
(-3675 4225);
DISPLAY 0.872340 (-3675 4225);
PAINT GREEN (-3675 4225);
DISPLAY INVISIBLE (-3675 4225);
FORCEPROP 1 LAST HDL_TAP TRUE
J 0
(-3350 4050);
DISPLAY 0.872340 (-3350 4050);
DISPLAY INVISIBLE (-3350 4050);
FORCEPROP 1 LAST PATH I380
J 0
(-3677 4175);
DISPLAY 0.872340 (-3677 4175);
PAINT GREEN (-3677 4175);
DISPLAY INVISIBLE (-3677 4175);
FORCEADD TAP..1
(-3675 4275);
FORCEPROP 3 LASTPIN (-3725 4275) SIG_NAME M_E_CPU0_SA_DQS_DP<5>
J 0
(-3715 4285);
DISPLAY 0.659574 (-3715 4285);
PAINT MONO (-3715 4285);
DISPLAY INVISIBLE (-3715 4285);
FORCEPROP 1 LASTPIN (-3725 4275) BN 5
J 0
(-3737 4283);
DISPLAY 0.489362 (-3737 4283);
PAINT GREEN (-3737 4283);
FORCEPROP 2 LAST CDS_LIB mstr_standard
J 0
(-3675 4275);
DISPLAY 0.723404 (-3675 4275);
PAINT MONO (-3675 4275);
DISPLAY INVISIBLE (-3675 4275);
FORCEPROP 1 LAST BODY_TYPE PLUMBING
J 0
(-3675 4325);
DISPLAY 0.872340 (-3675 4325);
PAINT GREEN (-3675 4325);
DISPLAY INVISIBLE (-3675 4325);
FORCEPROP 1 LAST HDL_TAP TRUE
J 0
(-3350 4150);
DISPLAY 0.872340 (-3350 4150);
DISPLAY INVISIBLE (-3350 4150);
FORCEPROP 1 LAST PATH I381
J 0
(-3677 4275);
DISPLAY 0.872340 (-3677 4275);
PAINT GREEN (-3677 4275);
DISPLAY INVISIBLE (-3677 4275);
FORCEADD TAP..1
(-3675 4075);
FORCEPROP 3 LASTPIN (-3725 4075) SIG_NAME M_E_CPU0_SA_DQS_DP<3>
J 0
(-3715 4085);
DISPLAY 0.659574 (-3715 4085);
PAINT MONO (-3715 4085);
DISPLAY INVISIBLE (-3715 4085);
FORCEPROP 1 LASTPIN (-3725 4075) BN 3
J 0
(-3737 4083);
DISPLAY 0.489362 (-3737 4083);
PAINT GREEN (-3737 4083);
FORCEPROP 2 LAST CDS_LIB mstr_standard
J 0
(-3675 4075);
DISPLAY 0.723404 (-3675 4075);
PAINT MONO (-3675 4075);
DISPLAY INVISIBLE (-3675 4075);
FORCEPROP 1 LAST BODY_TYPE PLUMBING
J 0
(-3675 4125);
DISPLAY 0.872340 (-3675 4125);
PAINT GREEN (-3675 4125);
DISPLAY INVISIBLE (-3675 4125);
FORCEPROP 1 LAST HDL_TAP TRUE
J 0
(-3350 3950);
DISPLAY 0.872340 (-3350 3950);
DISPLAY INVISIBLE (-3350 3950);
FORCEPROP 1 LAST PATH I382
J 0
(-3677 4075);
DISPLAY 0.872340 (-3677 4075);
PAINT GREEN (-3677 4075);
DISPLAY INVISIBLE (-3677 4075);
FORCEADD TAP..1
(-3475 3925);
FORCEPROP 3 LASTPIN (-3525 3925) SIG_NAME M_E_CPU0_SA_DQS_DN<2>
J 0
(-3515 3935);
DISPLAY 0.659574 (-3515 3935);
PAINT MONO (-3515 3935);
DISPLAY INVISIBLE (-3515 3935);
FORCEPROP 1 LASTPIN (-3525 3925) BN 2
J 0
(-3537 3933);
DISPLAY 0.489362 (-3537 3933);
PAINT GREEN (-3537 3933);
FORCEPROP 2 LAST CDS_LIB mstr_standard
J 0
(-3475 3925);
DISPLAY 0.723404 (-3475 3925);
PAINT MONO (-3475 3925);
DISPLAY INVISIBLE (-3475 3925);
FORCEPROP 1 LAST BODY_TYPE PLUMBING
J 0
(-3475 3975);
DISPLAY 0.872340 (-3475 3975);
PAINT GREEN (-3475 3975);
DISPLAY INVISIBLE (-3475 3975);
FORCEPROP 1 LAST HDL_TAP TRUE
J 0
(-3150 3800);
DISPLAY 0.872340 (-3150 3800);
DISPLAY INVISIBLE (-3150 3800);
FORCEPROP 1 LAST PATH I383
J 0
(-3477 3925);
DISPLAY 0.872340 (-3477 3925);
PAINT GREEN (-3477 3925);
DISPLAY INVISIBLE (-3477 3925);
FORCEADD TAP..1
(-3475 4025);
FORCEPROP 3 LASTPIN (-3525 4025) SIG_NAME M_E_CPU0_SA_DQS_DN<3>
J 0
(-3515 4035);
DISPLAY 0.659574 (-3515 4035);
PAINT MONO (-3515 4035);
DISPLAY INVISIBLE (-3515 4035);
FORCEPROP 1 LASTPIN (-3525 4025) BN 3
J 0
(-3537 4033);
DISPLAY 0.489362 (-3537 4033);
PAINT GREEN (-3537 4033);
FORCEPROP 2 LAST CDS_LIB mstr_standard
J 0
(-3475 4025);
DISPLAY 0.723404 (-3475 4025);
PAINT MONO (-3475 4025);
DISPLAY INVISIBLE (-3475 4025);
FORCEPROP 1 LAST BODY_TYPE PLUMBING
J 0
(-3475 4075);
DISPLAY 0.872340 (-3475 4075);
PAINT GREEN (-3475 4075);
DISPLAY INVISIBLE (-3475 4075);
FORCEPROP 1 LAST HDL_TAP TRUE
J 0
(-3150 3900);
DISPLAY 0.872340 (-3150 3900);
DISPLAY INVISIBLE (-3150 3900);
FORCEPROP 1 LAST PATH I384
J 0
(-3477 4025);
DISPLAY 0.872340 (-3477 4025);
PAINT GREEN (-3477 4025);
DISPLAY INVISIBLE (-3477 4025);
FORCEADD TAP..1
(-3475 3825);
FORCEPROP 3 LASTPIN (-3525 3825) SIG_NAME M_E_CPU0_SA_DQS_DN<1>
J 0
(-3515 3835);
DISPLAY 0.659574 (-3515 3835);
PAINT MONO (-3515 3835);
DISPLAY INVISIBLE (-3515 3835);
FORCEPROP 1 LASTPIN (-3525 3825) BN 1
J 0
(-3537 3833);
DISPLAY 0.489362 (-3537 3833);
PAINT GREEN (-3537 3833);
FORCEPROP 2 LAST CDS_LIB mstr_standard
J 0
(-3475 3825);
DISPLAY 0.723404 (-3475 3825);
PAINT MONO (-3475 3825);
DISPLAY INVISIBLE (-3475 3825);
FORCEPROP 1 LAST BODY_TYPE PLUMBING
J 0
(-3475 3875);
DISPLAY 0.872340 (-3475 3875);
PAINT GREEN (-3475 3875);
DISPLAY INVISIBLE (-3475 3875);
FORCEPROP 1 LAST HDL_TAP TRUE
J 0
(-3150 3700);
DISPLAY 0.872340 (-3150 3700);
DISPLAY INVISIBLE (-3150 3700);
FORCEPROP 1 LAST PATH I385
J 0
(-3477 3825);
DISPLAY 0.872340 (-3477 3825);
PAINT GREEN (-3477 3825);
DISPLAY INVISIBLE (-3477 3825);
FORCEADD TAP..1
(-3675 3975);
FORCEPROP 3 LASTPIN (-3725 3975) SIG_NAME M_E_CPU0_SA_DQS_DP<2>
J 0
(-3715 3985);
DISPLAY 0.659574 (-3715 3985);
PAINT MONO (-3715 3985);
DISPLAY INVISIBLE (-3715 3985);
FORCEPROP 1 LASTPIN (-3725 3975) BN 2
J 0
(-3737 3983);
DISPLAY 0.489362 (-3737 3983);
PAINT GREEN (-3737 3983);
FORCEPROP 2 LAST CDS_LIB mstr_standard
J 0
(-3675 3975);
DISPLAY 0.723404 (-3675 3975);
PAINT MONO (-3675 3975);
DISPLAY INVISIBLE (-3675 3975);
FORCEPROP 1 LAST BODY_TYPE PLUMBING
J 0
(-3675 4025);
DISPLAY 0.872340 (-3675 4025);
PAINT GREEN (-3675 4025);
DISPLAY INVISIBLE (-3675 4025);
FORCEPROP 1 LAST HDL_TAP TRUE
J 0
(-3350 3850);
DISPLAY 0.872340 (-3350 3850);
DISPLAY INVISIBLE (-3350 3850);
FORCEPROP 1 LAST PATH I386
J 0
(-3677 3975);
DISPLAY 0.872340 (-3677 3975);
PAINT GREEN (-3677 3975);
DISPLAY INVISIBLE (-3677 3975);
FORCEADD TAP..1
(-3675 3875);
FORCEPROP 3 LASTPIN (-3725 3875) SIG_NAME M_E_CPU0_SA_DQS_DP<1>
J 0
(-3715 3885);
DISPLAY 0.659574 (-3715 3885);
PAINT MONO (-3715 3885);
DISPLAY INVISIBLE (-3715 3885);
FORCEPROP 1 LASTPIN (-3725 3875) BN 1
J 0
(-3737 3883);
DISPLAY 0.489362 (-3737 3883);
PAINT GREEN (-3737 3883);
FORCEPROP 2 LAST CDS_LIB mstr_standard
J 0
(-3675 3875);
DISPLAY 0.723404 (-3675 3875);
PAINT MONO (-3675 3875);
DISPLAY INVISIBLE (-3675 3875);
FORCEPROP 1 LAST BODY_TYPE PLUMBING
J 0
(-3675 3925);
DISPLAY 0.872340 (-3675 3925);
PAINT GREEN (-3675 3925);
DISPLAY INVISIBLE (-3675 3925);
FORCEPROP 1 LAST HDL_TAP TRUE
J 0
(-3350 3750);
DISPLAY 0.872340 (-3350 3750);
DISPLAY INVISIBLE (-3350 3750);
FORCEPROP 1 LAST PATH I387
J 0
(-3677 3875);
DISPLAY 0.872340 (-3677 3875);
PAINT GREEN (-3677 3875);
DISPLAY INVISIBLE (-3677 3875);
FORCEADD TAP..1
(-3475 3575);
FORCEPROP 3 LASTPIN (-3525 3575) SIG_NAME M_E_CPU0_SB_DQS_DN<9>
J 0
(-3515 3585);
DISPLAY 0.659574 (-3515 3585);
PAINT MONO (-3515 3585);
DISPLAY INVISIBLE (-3515 3585);
FORCEPROP 1 LASTPIN (-3525 3575) BN 9
J 0
(-3537 3583);
DISPLAY 0.489362 (-3537 3583);
PAINT GREEN (-3537 3583);
FORCEPROP 2 LAST CDS_LIB mstr_standard
J 0
(-3475 3575);
DISPLAY 0.723404 (-3475 3575);
PAINT MONO (-3475 3575);
DISPLAY INVISIBLE (-3475 3575);
FORCEPROP 1 LAST BODY_TYPE PLUMBING
J 0
(-3475 3625);
DISPLAY 0.872340 (-3475 3625);
PAINT GREEN (-3475 3625);
DISPLAY INVISIBLE (-3475 3625);
FORCEPROP 1 LAST HDL_TAP TRUE
J 0
(-3150 3450);
DISPLAY 0.872340 (-3150 3450);
DISPLAY INVISIBLE (-3150 3450);
FORCEPROP 1 LAST PATH I388
J 0
(-3477 3575);
DISPLAY 0.872340 (-3477 3575);
PAINT GREEN (-3477 3575);
DISPLAY INVISIBLE (-3477 3575);
FORCEADD TAP..1
(-3475 3725);
FORCEPROP 3 LASTPIN (-3525 3725) SIG_NAME M_E_CPU0_SA_DQS_DN<0>
J 0
(-3515 3735);
DISPLAY 0.659574 (-3515 3735);
PAINT MONO (-3515 3735);
DISPLAY INVISIBLE (-3515 3735);
FORCEPROP 1 LASTPIN (-3525 3725) BN 0
J 0
(-3537 3733);
DISPLAY 0.489362 (-3537 3733);
PAINT GREEN (-3537 3733);
FORCEPROP 2 LAST CDS_LIB mstr_standard
J 0
(-3475 3725);
DISPLAY 0.723404 (-3475 3725);
PAINT MONO (-3475 3725);
DISPLAY INVISIBLE (-3475 3725);
FORCEPROP 1 LAST BODY_TYPE PLUMBING
J 0
(-3475 3775);
DISPLAY 0.872340 (-3475 3775);
PAINT GREEN (-3475 3775);
DISPLAY INVISIBLE (-3475 3775);
FORCEPROP 1 LAST HDL_TAP TRUE
J 0
(-3150 3600);
DISPLAY 0.872340 (-3150 3600);
DISPLAY INVISIBLE (-3150 3600);
FORCEPROP 1 LAST PATH I389
J 0
(-3477 3725);
DISPLAY 0.872340 (-3477 3725);
PAINT GREEN (-3477 3725);
DISPLAY INVISIBLE (-3477 3725);
FORCEADD TAP..1
(-3675 3775);
FORCEPROP 3 LASTPIN (-3725 3775) SIG_NAME M_E_CPU0_SA_DQS_DP<0>
J 0
(-3715 3785);
DISPLAY 0.659574 (-3715 3785);
PAINT MONO (-3715 3785);
DISPLAY INVISIBLE (-3715 3785);
FORCEPROP 1 LASTPIN (-3725 3775) BN 0
J 0
(-3737 3783);
DISPLAY 0.489362 (-3737 3783);
PAINT GREEN (-3737 3783);
FORCEPROP 2 LAST CDS_LIB mstr_standard
J 0
(-3675 3775);
DISPLAY 0.723404 (-3675 3775);
PAINT MONO (-3675 3775);
DISPLAY INVISIBLE (-3675 3775);
FORCEPROP 1 LAST BODY_TYPE PLUMBING
J 0
(-3675 3825);
DISPLAY 0.872340 (-3675 3825);
PAINT GREEN (-3675 3825);
DISPLAY INVISIBLE (-3675 3825);
FORCEPROP 1 LAST HDL_TAP TRUE
J 0
(-3350 3650);
DISPLAY 0.872340 (-3350 3650);
DISPLAY INVISIBLE (-3350 3650);
FORCEPROP 1 LAST PATH I390
J 0
(-3677 3775);
DISPLAY 0.872340 (-3677 3775);
PAINT GREEN (-3677 3775);
DISPLAY INVISIBLE (-3677 3775);
FORCEADD TAP..1
(-3675 3625);
FORCEPROP 3 LASTPIN (-3725 3625) SIG_NAME M_E_CPU0_SB_DQS_DP<9>
J 0
(-3715 3635);
DISPLAY 0.659574 (-3715 3635);
PAINT MONO (-3715 3635);
DISPLAY INVISIBLE (-3715 3635);
FORCEPROP 1 LASTPIN (-3725 3625) BN 9
J 0
(-3737 3633);
DISPLAY 0.489362 (-3737 3633);
PAINT GREEN (-3737 3633);
FORCEPROP 2 LAST CDS_LIB mstr_standard
J 0
(-3675 3625);
DISPLAY 0.723404 (-3675 3625);
PAINT MONO (-3675 3625);
DISPLAY INVISIBLE (-3675 3625);
FORCEPROP 1 LAST BODY_TYPE PLUMBING
J 0
(-3675 3675);
DISPLAY 0.872340 (-3675 3675);
PAINT GREEN (-3675 3675);
DISPLAY INVISIBLE (-3675 3675);
FORCEPROP 1 LAST HDL_TAP TRUE
J 0
(-3350 3500);
DISPLAY 0.872340 (-3350 3500);
DISPLAY INVISIBLE (-3350 3500);
FORCEPROP 1 LAST PATH I391
J 0
(-3677 3625);
DISPLAY 0.872340 (-3677 3625);
PAINT GREEN (-3677 3625);
DISPLAY INVISIBLE (-3677 3625);
FORCEADD TAP..1
(-3475 3475);
FORCEPROP 3 LASTPIN (-3525 3475) SIG_NAME M_E_CPU0_SB_DQS_DN<8>
J 0
(-3515 3485);
DISPLAY 0.659574 (-3515 3485);
PAINT MONO (-3515 3485);
DISPLAY INVISIBLE (-3515 3485);
FORCEPROP 1 LASTPIN (-3525 3475) BN 8
J 0
(-3537 3483);
DISPLAY 0.489362 (-3537 3483);
PAINT GREEN (-3537 3483);
FORCEPROP 2 LAST CDS_LIB mstr_standard
J 0
(-3475 3475);
DISPLAY 0.723404 (-3475 3475);
PAINT MONO (-3475 3475);
DISPLAY INVISIBLE (-3475 3475);
FORCEPROP 1 LAST BODY_TYPE PLUMBING
J 0
(-3475 3525);
DISPLAY 0.872340 (-3475 3525);
PAINT GREEN (-3475 3525);
DISPLAY INVISIBLE (-3475 3525);
FORCEPROP 1 LAST HDL_TAP TRUE
J 0
(-3150 3350);
DISPLAY 0.872340 (-3150 3350);
DISPLAY INVISIBLE (-3150 3350);
FORCEPROP 1 LAST PATH I392
J 0
(-3477 3475);
DISPLAY 0.872340 (-3477 3475);
PAINT GREEN (-3477 3475);
DISPLAY INVISIBLE (-3477 3475);
FORCEADD TAP..1
(-3475 3275);
FORCEPROP 3 LASTPIN (-3525 3275) SIG_NAME M_E_CPU0_SB_DQS_DN<6>
J 0
(-3515 3285);
DISPLAY 0.659574 (-3515 3285);
PAINT MONO (-3515 3285);
DISPLAY INVISIBLE (-3515 3285);
FORCEPROP 1 LASTPIN (-3525 3275) BN 6
J 0
(-3537 3283);
DISPLAY 0.489362 (-3537 3283);
PAINT GREEN (-3537 3283);
FORCEPROP 2 LAST CDS_LIB mstr_standard
J 0
(-3475 3275);
DISPLAY 0.723404 (-3475 3275);
PAINT MONO (-3475 3275);
DISPLAY INVISIBLE (-3475 3275);
FORCEPROP 1 LAST BODY_TYPE PLUMBING
J 0
(-3475 3325);
DISPLAY 0.872340 (-3475 3325);
PAINT GREEN (-3475 3325);
DISPLAY INVISIBLE (-3475 3325);
FORCEPROP 1 LAST HDL_TAP TRUE
J 0
(-3150 3150);
DISPLAY 0.872340 (-3150 3150);
DISPLAY INVISIBLE (-3150 3150);
FORCEPROP 1 LAST PATH I393
J 0
(-3477 3275);
DISPLAY 0.872340 (-3477 3275);
PAINT GREEN (-3477 3275);
DISPLAY INVISIBLE (-3477 3275);
FORCEADD TAP..1
(-3475 3375);
FORCEPROP 3 LASTPIN (-3525 3375) SIG_NAME M_E_CPU0_SB_DQS_DN<7>
J 0
(-3515 3385);
DISPLAY 0.659574 (-3515 3385);
PAINT MONO (-3515 3385);
DISPLAY INVISIBLE (-3515 3385);
FORCEPROP 1 LASTPIN (-3525 3375) BN 7
J 0
(-3537 3383);
DISPLAY 0.489362 (-3537 3383);
PAINT GREEN (-3537 3383);
FORCEPROP 2 LAST CDS_LIB mstr_standard
J 0
(-3475 3375);
DISPLAY 0.723404 (-3475 3375);
PAINT MONO (-3475 3375);
DISPLAY INVISIBLE (-3475 3375);
FORCEPROP 1 LAST BODY_TYPE PLUMBING
J 0
(-3475 3425);
DISPLAY 0.872340 (-3475 3425);
PAINT GREEN (-3475 3425);
DISPLAY INVISIBLE (-3475 3425);
FORCEPROP 1 LAST HDL_TAP TRUE
J 0
(-3150 3250);
DISPLAY 0.872340 (-3150 3250);
DISPLAY INVISIBLE (-3150 3250);
FORCEPROP 1 LAST PATH I394
J 0
(-3477 3375);
DISPLAY 0.872340 (-3477 3375);
PAINT GREEN (-3477 3375);
DISPLAY INVISIBLE (-3477 3375);
FORCEADD TAP..1
(-3675 3525);
FORCEPROP 3 LASTPIN (-3725 3525) SIG_NAME M_E_CPU0_SB_DQS_DP<8>
J 0
(-3715 3535);
DISPLAY 0.659574 (-3715 3535);
PAINT MONO (-3715 3535);
DISPLAY INVISIBLE (-3715 3535);
FORCEPROP 1 LASTPIN (-3725 3525) BN 8
J 0
(-3737 3533);
DISPLAY 0.489362 (-3737 3533);
PAINT GREEN (-3737 3533);
FORCEPROP 2 LAST CDS_LIB mstr_standard
J 0
(-3675 3525);
DISPLAY 0.723404 (-3675 3525);
PAINT MONO (-3675 3525);
DISPLAY INVISIBLE (-3675 3525);
FORCEPROP 1 LAST BODY_TYPE PLUMBING
J 0
(-3675 3575);
DISPLAY 0.872340 (-3675 3575);
PAINT GREEN (-3675 3575);
DISPLAY INVISIBLE (-3675 3575);
FORCEPROP 1 LAST HDL_TAP TRUE
J 0
(-3350 3400);
DISPLAY 0.872340 (-3350 3400);
DISPLAY INVISIBLE (-3350 3400);
FORCEPROP 1 LAST PATH I395
J 0
(-3677 3525);
DISPLAY 0.872340 (-3677 3525);
PAINT GREEN (-3677 3525);
DISPLAY INVISIBLE (-3677 3525);
FORCEADD TAP..1
(-3675 3425);
FORCEPROP 3 LASTPIN (-3725 3425) SIG_NAME M_E_CPU0_SB_DQS_DP<7>
J 0
(-3715 3435);
DISPLAY 0.659574 (-3715 3435);
PAINT MONO (-3715 3435);
DISPLAY INVISIBLE (-3715 3435);
FORCEPROP 1 LASTPIN (-3725 3425) BN 7
J 0
(-3737 3433);
DISPLAY 0.489362 (-3737 3433);
PAINT GREEN (-3737 3433);
FORCEPROP 2 LAST CDS_LIB mstr_standard
J 0
(-3675 3425);
DISPLAY 0.723404 (-3675 3425);
PAINT MONO (-3675 3425);
DISPLAY INVISIBLE (-3675 3425);
FORCEPROP 1 LAST BODY_TYPE PLUMBING
J 0
(-3675 3475);
DISPLAY 0.872340 (-3675 3475);
PAINT GREEN (-3675 3475);
DISPLAY INVISIBLE (-3675 3475);
FORCEPROP 1 LAST HDL_TAP TRUE
J 0
(-3350 3300);
DISPLAY 0.872340 (-3350 3300);
DISPLAY INVISIBLE (-3350 3300);
FORCEPROP 1 LAST PATH I396
J 0
(-3677 3425);
DISPLAY 0.872340 (-3677 3425);
PAINT GREEN (-3677 3425);
DISPLAY INVISIBLE (-3677 3425);
FORCEADD TAP..1
(-3675 3325);
FORCEPROP 3 LASTPIN (-3725 3325) SIG_NAME M_E_CPU0_SB_DQS_DP<6>
J 0
(-3715 3335);
DISPLAY 0.659574 (-3715 3335);
PAINT MONO (-3715 3335);
DISPLAY INVISIBLE (-3715 3335);
FORCEPROP 1 LASTPIN (-3725 3325) BN 6
J 0
(-3737 3333);
DISPLAY 0.489362 (-3737 3333);
PAINT GREEN (-3737 3333);
FORCEPROP 2 LAST CDS_LIB mstr_standard
J 0
(-3675 3325);
DISPLAY 0.723404 (-3675 3325);
PAINT MONO (-3675 3325);
DISPLAY INVISIBLE (-3675 3325);
FORCEPROP 1 LAST BODY_TYPE PLUMBING
J 0
(-3675 3375);
DISPLAY 0.872340 (-3675 3375);
PAINT GREEN (-3675 3375);
DISPLAY INVISIBLE (-3675 3375);
FORCEPROP 1 LAST HDL_TAP TRUE
J 0
(-3350 3200);
DISPLAY 0.872340 (-3350 3200);
DISPLAY INVISIBLE (-3350 3200);
FORCEPROP 1 LAST PATH I397
J 0
(-3677 3325);
DISPLAY 0.872340 (-3677 3325);
PAINT GREEN (-3677 3325);
DISPLAY INVISIBLE (-3677 3325);
FORCEADD TAP..1
(-3475 3075);
FORCEPROP 3 LASTPIN (-3525 3075) SIG_NAME M_E_CPU0_SB_DQS_DN<4>
J 0
(-3515 3085);
DISPLAY 0.659574 (-3515 3085);
PAINT MONO (-3515 3085);
DISPLAY INVISIBLE (-3515 3085);
FORCEPROP 1 LASTPIN (-3525 3075) BN 4
J 0
(-3537 3083);
DISPLAY 0.489362 (-3537 3083);
PAINT GREEN (-3537 3083);
FORCEPROP 2 LAST CDS_LIB mstr_standard
J 0
(-3475 3075);
DISPLAY 0.723404 (-3475 3075);
PAINT MONO (-3475 3075);
DISPLAY INVISIBLE (-3475 3075);
FORCEPROP 1 LAST BODY_TYPE PLUMBING
J 0
(-3475 3125);
DISPLAY 0.872340 (-3475 3125);
PAINT GREEN (-3475 3125);
DISPLAY INVISIBLE (-3475 3125);
FORCEPROP 1 LAST HDL_TAP TRUE
J 0
(-3150 2950);
DISPLAY 0.872340 (-3150 2950);
DISPLAY INVISIBLE (-3150 2950);
FORCEPROP 1 LAST PATH I398
J 0
(-3477 3075);
DISPLAY 0.872340 (-3477 3075);
PAINT GREEN (-3477 3075);
DISPLAY INVISIBLE (-3477 3075);
FORCEADD TAP..1
(-3475 3175);
FORCEPROP 3 LASTPIN (-3525 3175) SIG_NAME M_E_CPU0_SB_DQS_DN<5>
J 0
(-3515 3185);
DISPLAY 0.659574 (-3515 3185);
PAINT MONO (-3515 3185);
DISPLAY INVISIBLE (-3515 3185);
FORCEPROP 1 LASTPIN (-3525 3175) BN 5
J 0
(-3537 3183);
DISPLAY 0.489362 (-3537 3183);
PAINT GREEN (-3537 3183);
FORCEPROP 2 LAST CDS_LIB mstr_standard
J 0
(-3475 3175);
DISPLAY 0.723404 (-3475 3175);
PAINT MONO (-3475 3175);
DISPLAY INVISIBLE (-3475 3175);
FORCEPROP 1 LAST BODY_TYPE PLUMBING
J 0
(-3475 3225);
DISPLAY 0.872340 (-3475 3225);
PAINT GREEN (-3475 3225);
DISPLAY INVISIBLE (-3475 3225);
FORCEPROP 1 LAST HDL_TAP TRUE
J 0
(-3150 3050);
DISPLAY 0.872340 (-3150 3050);
DISPLAY INVISIBLE (-3150 3050);
FORCEPROP 1 LAST PATH I399
J 0
(-3477 3175);
DISPLAY 0.872340 (-3477 3175);
PAINT GREEN (-3477 3175);
DISPLAY INVISIBLE (-3477 3175);
FORCEADD TAP..1
(-3675 3225);
FORCEPROP 3 LASTPIN (-3725 3225) SIG_NAME M_E_CPU0_SB_DQS_DP<5>
J 0
(-3715 3235);
DISPLAY 0.659574 (-3715 3235);
PAINT MONO (-3715 3235);
DISPLAY INVISIBLE (-3715 3235);
FORCEPROP 1 LASTPIN (-3725 3225) BN 5
J 0
(-3737 3233);
DISPLAY 0.489362 (-3737 3233);
PAINT GREEN (-3737 3233);
FORCEPROP 2 LAST CDS_LIB mstr_standard
J 0
(-3675 3225);
DISPLAY 0.723404 (-3675 3225);
PAINT MONO (-3675 3225);
DISPLAY INVISIBLE (-3675 3225);
FORCEPROP 1 LAST BODY_TYPE PLUMBING
J 0
(-3675 3275);
DISPLAY 0.872340 (-3675 3275);
PAINT GREEN (-3675 3275);
DISPLAY INVISIBLE (-3675 3275);
FORCEPROP 1 LAST HDL_TAP TRUE
J 0
(-3350 3100);
DISPLAY 0.872340 (-3350 3100);
DISPLAY INVISIBLE (-3350 3100);
FORCEPROP 1 LAST PATH I400
J 0
(-3677 3225);
DISPLAY 0.872340 (-3677 3225);
PAINT GREEN (-3677 3225);
DISPLAY INVISIBLE (-3677 3225);
FORCEADD TAP..1
(-3675 3025);
FORCEPROP 3 LASTPIN (-3725 3025) SIG_NAME M_E_CPU0_SB_DQS_DP<3>
J 0
(-3715 3035);
DISPLAY 0.659574 (-3715 3035);
PAINT MONO (-3715 3035);
DISPLAY INVISIBLE (-3715 3035);
FORCEPROP 1 LASTPIN (-3725 3025) BN 3
J 0
(-3737 3033);
DISPLAY 0.489362 (-3737 3033);
PAINT GREEN (-3737 3033);
FORCEPROP 2 LAST CDS_LIB mstr_standard
J 0
(-3675 3025);
DISPLAY 0.723404 (-3675 3025);
PAINT MONO (-3675 3025);
DISPLAY INVISIBLE (-3675 3025);
FORCEPROP 1 LAST BODY_TYPE PLUMBING
J 0
(-3675 3075);
DISPLAY 0.872340 (-3675 3075);
PAINT GREEN (-3675 3075);
DISPLAY INVISIBLE (-3675 3075);
FORCEPROP 1 LAST HDL_TAP TRUE
J 0
(-3350 2900);
DISPLAY 0.872340 (-3350 2900);
DISPLAY INVISIBLE (-3350 2900);
FORCEPROP 1 LAST PATH I401
J 0
(-3677 3025);
DISPLAY 0.872340 (-3677 3025);
PAINT GREEN (-3677 3025);
DISPLAY INVISIBLE (-3677 3025);
FORCEADD TAP..1
(-3675 3125);
FORCEPROP 3 LASTPIN (-3725 3125) SIG_NAME M_E_CPU0_SB_DQS_DP<4>
J 0
(-3715 3135);
DISPLAY 0.659574 (-3715 3135);
PAINT MONO (-3715 3135);
DISPLAY INVISIBLE (-3715 3135);
FORCEPROP 1 LASTPIN (-3725 3125) BN 4
J 0
(-3737 3133);
DISPLAY 0.489362 (-3737 3133);
PAINT GREEN (-3737 3133);
FORCEPROP 2 LAST CDS_LIB mstr_standard
J 0
(-3675 3125);
DISPLAY 0.723404 (-3675 3125);
PAINT MONO (-3675 3125);
DISPLAY INVISIBLE (-3675 3125);
FORCEPROP 1 LAST BODY_TYPE PLUMBING
J 0
(-3675 3175);
DISPLAY 0.872340 (-3675 3175);
PAINT GREEN (-3675 3175);
DISPLAY INVISIBLE (-3675 3175);
FORCEPROP 1 LAST HDL_TAP TRUE
J 0
(-3350 3000);
DISPLAY 0.872340 (-3350 3000);
DISPLAY INVISIBLE (-3350 3000);
FORCEPROP 1 LAST PATH I402
J 0
(-3677 3125);
DISPLAY 0.872340 (-3677 3125);
PAINT GREEN (-3677 3125);
DISPLAY INVISIBLE (-3677 3125);
FORCEADD TAP..1
(-3475 2975);
FORCEPROP 3 LASTPIN (-3525 2975) SIG_NAME M_E_CPU0_SB_DQS_DN<3>
J 0
(-3515 2985);
DISPLAY 0.659574 (-3515 2985);
PAINT MONO (-3515 2985);
DISPLAY INVISIBLE (-3515 2985);
FORCEPROP 1 LASTPIN (-3525 2975) BN 3
J 0
(-3537 2983);
DISPLAY 0.489362 (-3537 2983);
PAINT GREEN (-3537 2983);
FORCEPROP 2 LAST CDS_LIB mstr_standard
J 0
(-3475 2975);
DISPLAY 0.723404 (-3475 2975);
PAINT MONO (-3475 2975);
DISPLAY INVISIBLE (-3475 2975);
FORCEPROP 1 LAST BODY_TYPE PLUMBING
J 0
(-3475 3025);
DISPLAY 0.872340 (-3475 3025);
PAINT GREEN (-3475 3025);
DISPLAY INVISIBLE (-3475 3025);
FORCEPROP 1 LAST HDL_TAP TRUE
J 0
(-3150 2850);
DISPLAY 0.872340 (-3150 2850);
DISPLAY INVISIBLE (-3150 2850);
FORCEPROP 1 LAST PATH I403
J 0
(-3477 2975);
DISPLAY 0.872340 (-3477 2975);
PAINT GREEN (-3477 2975);
DISPLAY INVISIBLE (-3477 2975);
FORCEADD TAP..1
(-3475 2775);
FORCEPROP 3 LASTPIN (-3525 2775) SIG_NAME M_E_CPU0_SB_DQS_DN<1>
J 0
(-3515 2785);
DISPLAY 0.659574 (-3515 2785);
PAINT MONO (-3515 2785);
DISPLAY INVISIBLE (-3515 2785);
FORCEPROP 1 LASTPIN (-3525 2775) BN 1
J 0
(-3537 2783);
DISPLAY 0.489362 (-3537 2783);
PAINT GREEN (-3537 2783);
FORCEPROP 2 LAST CDS_LIB mstr_standard
J 0
(-3475 2775);
DISPLAY 0.723404 (-3475 2775);
PAINT MONO (-3475 2775);
DISPLAY INVISIBLE (-3475 2775);
FORCEPROP 1 LAST BODY_TYPE PLUMBING
J 0
(-3475 2825);
DISPLAY 0.872340 (-3475 2825);
PAINT GREEN (-3475 2825);
DISPLAY INVISIBLE (-3475 2825);
FORCEPROP 1 LAST HDL_TAP TRUE
J 0
(-3150 2650);
DISPLAY 0.872340 (-3150 2650);
DISPLAY INVISIBLE (-3150 2650);
FORCEPROP 1 LAST PATH I404
J 0
(-3477 2775);
DISPLAY 0.872340 (-3477 2775);
PAINT GREEN (-3477 2775);
DISPLAY INVISIBLE (-3477 2775);
FORCEADD TAP..1
(-3475 2875);
FORCEPROP 3 LASTPIN (-3525 2875) SIG_NAME M_E_CPU0_SB_DQS_DN<2>
J 0
(-3515 2885);
DISPLAY 0.659574 (-3515 2885);
PAINT MONO (-3515 2885);
DISPLAY INVISIBLE (-3515 2885);
FORCEPROP 1 LASTPIN (-3525 2875) BN 2
J 0
(-3537 2883);
DISPLAY 0.489362 (-3537 2883);
PAINT GREEN (-3537 2883);
FORCEPROP 2 LAST CDS_LIB mstr_standard
J 0
(-3475 2875);
DISPLAY 0.723404 (-3475 2875);
PAINT MONO (-3475 2875);
DISPLAY INVISIBLE (-3475 2875);
FORCEPROP 1 LAST BODY_TYPE PLUMBING
J 0
(-3475 2925);
DISPLAY 0.872340 (-3475 2925);
PAINT GREEN (-3475 2925);
DISPLAY INVISIBLE (-3475 2925);
FORCEPROP 1 LAST HDL_TAP TRUE
J 0
(-3150 2750);
DISPLAY 0.872340 (-3150 2750);
DISPLAY INVISIBLE (-3150 2750);
FORCEPROP 1 LAST PATH I405
J 0
(-3477 2875);
DISPLAY 0.872340 (-3477 2875);
PAINT GREEN (-3477 2875);
DISPLAY INVISIBLE (-3477 2875);
FORCEADD TAP..1
(-3675 2925);
FORCEPROP 3 LASTPIN (-3725 2925) SIG_NAME M_E_CPU0_SB_DQS_DP<2>
J 0
(-3715 2935);
DISPLAY 0.659574 (-3715 2935);
PAINT MONO (-3715 2935);
DISPLAY INVISIBLE (-3715 2935);
FORCEPROP 1 LASTPIN (-3725 2925) BN 2
J 0
(-3737 2933);
DISPLAY 0.489362 (-3737 2933);
PAINT GREEN (-3737 2933);
FORCEPROP 2 LAST CDS_LIB mstr_standard
J 0
(-3675 2925);
DISPLAY 0.723404 (-3675 2925);
PAINT MONO (-3675 2925);
DISPLAY INVISIBLE (-3675 2925);
FORCEPROP 1 LAST BODY_TYPE PLUMBING
J 0
(-3675 2975);
DISPLAY 0.872340 (-3675 2975);
PAINT GREEN (-3675 2975);
DISPLAY INVISIBLE (-3675 2975);
FORCEPROP 1 LAST HDL_TAP TRUE
J 0
(-3350 2800);
DISPLAY 0.872340 (-3350 2800);
DISPLAY INVISIBLE (-3350 2800);
FORCEPROP 1 LAST PATH I406
J 0
(-3677 2925);
DISPLAY 0.872340 (-3677 2925);
PAINT GREEN (-3677 2925);
DISPLAY INVISIBLE (-3677 2925);
FORCEADD TAP..1
(-3675 2825);
FORCEPROP 3 LASTPIN (-3725 2825) SIG_NAME M_E_CPU0_SB_DQS_DP<1>
J 0
(-3715 2835);
DISPLAY 0.659574 (-3715 2835);
PAINT MONO (-3715 2835);
DISPLAY INVISIBLE (-3715 2835);
FORCEPROP 1 LASTPIN (-3725 2825) BN 1
J 0
(-3737 2833);
DISPLAY 0.489362 (-3737 2833);
PAINT GREEN (-3737 2833);
FORCEPROP 2 LAST CDS_LIB mstr_standard
J 0
(-3675 2825);
DISPLAY 0.723404 (-3675 2825);
PAINT MONO (-3675 2825);
DISPLAY INVISIBLE (-3675 2825);
FORCEPROP 1 LAST BODY_TYPE PLUMBING
J 0
(-3675 2875);
DISPLAY 0.872340 (-3675 2875);
PAINT GREEN (-3675 2875);
DISPLAY INVISIBLE (-3675 2875);
FORCEPROP 1 LAST HDL_TAP TRUE
J 0
(-3350 2700);
DISPLAY 0.872340 (-3350 2700);
DISPLAY INVISIBLE (-3350 2700);
FORCEPROP 1 LAST PATH I407
J 0
(-3677 2825);
DISPLAY 0.872340 (-3677 2825);
PAINT GREEN (-3677 2825);
DISPLAY INVISIBLE (-3677 2825);
FORCEADD TAP..1
(-3475 2675);
FORCEPROP 3 LASTPIN (-3525 2675) SIG_NAME M_E_CPU0_SB_DQS_DN<0>
J 0
(-3515 2685);
DISPLAY 0.659574 (-3515 2685);
PAINT MONO (-3515 2685);
DISPLAY INVISIBLE (-3515 2685);
FORCEPROP 1 LASTPIN (-3525 2675) BN 0
J 0
(-3537 2683);
DISPLAY 0.489362 (-3537 2683);
PAINT GREEN (-3537 2683);
FORCEPROP 2 LAST CDS_LIB mstr_standard
J 0
(-3475 2675);
DISPLAY 0.723404 (-3475 2675);
PAINT MONO (-3475 2675);
DISPLAY INVISIBLE (-3475 2675);
FORCEPROP 1 LAST BODY_TYPE PLUMBING
J 0
(-3475 2725);
DISPLAY 0.872340 (-3475 2725);
PAINT GREEN (-3475 2725);
DISPLAY INVISIBLE (-3475 2725);
FORCEPROP 1 LAST HDL_TAP TRUE
J 0
(-3150 2550);
DISPLAY 0.872340 (-3150 2550);
DISPLAY INVISIBLE (-3150 2550);
FORCEPROP 1 LAST PATH I408
J 0
(-3477 2675);
DISPLAY 0.872340 (-3477 2675);
PAINT GREEN (-3477 2675);
DISPLAY INVISIBLE (-3477 2675);
FORCEADD TAP..1
(-3675 2725);
FORCEPROP 3 LASTPIN (-3725 2725) SIG_NAME M_E_CPU0_SB_DQS_DP<0>
J 0
(-3715 2735);
DISPLAY 0.659574 (-3715 2735);
PAINT MONO (-3715 2735);
DISPLAY INVISIBLE (-3715 2735);
FORCEPROP 1 LASTPIN (-3725 2725) BN 0
J 0
(-3737 2733);
DISPLAY 0.489362 (-3737 2733);
PAINT GREEN (-3737 2733);
FORCEPROP 2 LAST CDS_LIB mstr_standard
J 0
(-3675 2725);
DISPLAY 0.723404 (-3675 2725);
PAINT MONO (-3675 2725);
DISPLAY INVISIBLE (-3675 2725);
FORCEPROP 1 LAST BODY_TYPE PLUMBING
J 0
(-3675 2775);
DISPLAY 0.872340 (-3675 2775);
PAINT GREEN (-3675 2775);
DISPLAY INVISIBLE (-3675 2775);
FORCEPROP 1 LAST HDL_TAP TRUE
J 0
(-3350 2600);
DISPLAY 0.872340 (-3350 2600);
DISPLAY INVISIBLE (-3350 2600);
FORCEPROP 1 LAST PATH I409
J 0
(-3677 2725);
DISPLAY 0.872340 (-3677 2725);
PAINT GREEN (-3677 2725);
DISPLAY INVISIBLE (-3677 2725);
FORCEADD SCONN288_DDR506112002KQ..2
(-4625 3675);
FORCEPROP 1 LAST LOCATION J21
J 0
(-5225 5000);
DISPLAY 0.468085 (-5225 5000);
PAINT SKYBLUE (-5225 5000);
FORCEPROP 0 LAST $SEC 2
J 0
(-5075 5150);
DISPLAY 0.680851 (-5075 5150);
PAINT MONO (-5075 5150);
DISPLAY INVISIBLE (-5075 5150);
FORCEPROP 0 LAST CDS_SEC 2
J 0
(-5075 5150);
DISPLAY 1.021277 (-5075 5150);
DISPLAY INVISIBLE (-5075 5150);
FORCEPROP 0 LASTPIN (-3875 3725) $PN 12
J 0
(-3865 3735);
DISPLAY 0.680851 (-3865 3735);
PAINT MONO (-3865 3735);
FORCEPROP 0 LASTPIN (-3875 3775) $PN 11
J 0
(-3865 3785);
DISPLAY 0.680851 (-3865 3785);
PAINT MONO (-3865 3785);
FORCEPROP 0 LASTPIN (-3875 2675) $PN 105
J 0
(-3865 2685);
DISPLAY 0.680851 (-3865 2685);
PAINT MONO (-3865 2685);
FORCEPROP 0 LASTPIN (-3875 2725) $PN 104
J 0
(-3865 2735);
DISPLAY 0.680851 (-3865 2735);
PAINT MONO (-3865 2735);
FORCEPROP 0 LASTPIN (-3875 3825) $PN 23
J 0
(-3865 3835);
DISPLAY 0.680851 (-3865 3835);
PAINT MONO (-3865 3835);
FORCEPROP 0 LASTPIN (-3875 3875) $PN 22
J 0
(-3865 3885);
DISPLAY 0.680851 (-3865 3885);
PAINT MONO (-3865 3885);
FORCEPROP 0 LASTPIN (-3875 2775) $PN 116
J 0
(-3865 2785);
DISPLAY 0.680851 (-3865 2785);
PAINT MONO (-3865 2785);
FORCEPROP 0 LASTPIN (-3875 2825) $PN 115
J 0
(-3865 2835);
DISPLAY 0.680851 (-3865 2835);
PAINT MONO (-3865 2835);
FORCEPROP 0 LASTPIN (-3875 3925) $PN 34
J 0
(-3865 3935);
DISPLAY 0.680851 (-3865 3935);
PAINT MONO (-3865 3935);
FORCEPROP 0 LASTPIN (-3875 3975) $PN 33
J 0
(-3865 3985);
DISPLAY 0.680851 (-3865 3985);
PAINT MONO (-3865 3985);
FORCEPROP 0 LASTPIN (-3875 2875) $PN 127
J 0
(-3865 2885);
DISPLAY 0.680851 (-3865 2885);
PAINT MONO (-3865 2885);
FORCEPROP 0 LASTPIN (-3875 2925) $PN 126
J 0
(-3865 2935);
DISPLAY 0.680851 (-3865 2935);
PAINT MONO (-3865 2935);
FORCEPROP 0 LASTPIN (-3875 4025) $PN 45
J 0
(-3865 4035);
DISPLAY 0.680851 (-3865 4035);
PAINT MONO (-3865 4035);
FORCEPROP 0 LASTPIN (-3875 4075) $PN 44
J 0
(-3865 4085);
DISPLAY 0.680851 (-3865 4085);
PAINT MONO (-3865 4085);
FORCEPROP 0 LASTPIN (-3875 2975) $PN 138
J 0
(-3865 2985);
DISPLAY 0.680851 (-3865 2985);
PAINT MONO (-3865 2985);
FORCEPROP 0 LASTPIN (-3875 3025) $PN 137
J 0
(-3865 3035);
DISPLAY 0.680851 (-3865 3035);
PAINT MONO (-3865 3035);
FORCEPROP 0 LASTPIN (-3875 4125) $PN 56
J 0
(-3865 4135);
DISPLAY 0.680851 (-3865 4135);
PAINT MONO (-3865 4135);
FORCEPROP 0 LASTPIN (-3875 4175) $PN 55
J 0
(-3865 4185);
DISPLAY 0.680851 (-3865 4185);
PAINT MONO (-3865 4185);
FORCEPROP 0 LASTPIN (-3875 3075) $PN 238
J 0
(-3865 3085);
DISPLAY 0.680851 (-3865 3085);
PAINT MONO (-3865 3085);
FORCEPROP 0 LASTPIN (-3875 3125) $PN 239
J 0
(-3865 3135);
DISPLAY 0.680851 (-3865 3135);
PAINT MONO (-3865 3135);
FORCEPROP 0 LASTPIN (-3875 4225) $PN 156
J 0
(-3865 4235);
DISPLAY 0.680851 (-3865 4235);
PAINT MONO (-3865 4235);
FORCEPROP 0 LASTPIN (-3875 4275) $PN 157
J 0
(-3865 4285);
DISPLAY 0.680851 (-3865 4285);
PAINT MONO (-3865 4285);
FORCEPROP 0 LASTPIN (-3875 3175) $PN 249
J 0
(-3865 3185);
DISPLAY 0.680851 (-3865 3185);
PAINT MONO (-3865 3185);
FORCEPROP 0 LASTPIN (-3875 3225) $PN 250
J 0
(-3865 3235);
DISPLAY 0.680851 (-3865 3235);
PAINT MONO (-3865 3235);
FORCEPROP 0 LASTPIN (-3875 4325) $PN 167
J 0
(-3865 4335);
DISPLAY 0.680851 (-3865 4335);
PAINT MONO (-3865 4335);
FORCEPROP 0 LASTPIN (-3875 4375) $PN 168
J 0
(-3865 4385);
DISPLAY 0.680851 (-3865 4385);
PAINT MONO (-3865 4385);
FORCEPROP 0 LASTPIN (-3875 3275) $PN 260
J 0
(-3865 3285);
DISPLAY 0.680851 (-3865 3285);
PAINT MONO (-3865 3285);
FORCEPROP 0 LASTPIN (-3875 3325) $PN 261
J 0
(-3865 3335);
DISPLAY 0.680851 (-3865 3335);
PAINT MONO (-3865 3335);
FORCEPROP 0 LASTPIN (-3875 4425) $PN 178
J 0
(-3865 4435);
DISPLAY 0.680851 (-3865 4435);
PAINT MONO (-3865 4435);
FORCEPROP 0 LASTPIN (-3875 4475) $PN 179
J 0
(-3865 4485);
DISPLAY 0.680851 (-3865 4485);
PAINT MONO (-3865 4485);
FORCEPROP 0 LASTPIN (-3875 3375) $PN 271
J 0
(-3865 3385);
DISPLAY 0.680851 (-3865 3385);
PAINT MONO (-3865 3385);
FORCEPROP 0 LASTPIN (-3875 3425) $PN 272
J 0
(-3865 3435);
DISPLAY 0.680851 (-3865 3435);
PAINT MONO (-3865 3435);
FORCEPROP 0 LASTPIN (-3875 4525) $PN 189
J 0
(-3865 4535);
DISPLAY 0.680851 (-3865 4535);
PAINT MONO (-3865 4535);
FORCEPROP 0 LASTPIN (-3875 4575) $PN 190
J 0
(-3865 4585);
DISPLAY 0.680851 (-3865 4585);
PAINT MONO (-3865 4585);
FORCEPROP 0 LASTPIN (-3875 3475) $PN 282
J 0
(-3865 3485);
DISPLAY 0.680851 (-3865 3485);
PAINT MONO (-3865 3485);
FORCEPROP 0 LASTPIN (-3875 3525) $PN 283
J 0
(-3865 3535);
DISPLAY 0.680851 (-3865 3535);
PAINT MONO (-3865 3535);
FORCEPROP 0 LASTPIN (-3875 4625) $PN 200
J 0
(-3865 4635);
DISPLAY 0.680851 (-3865 4635);
PAINT MONO (-3865 4635);
FORCEPROP 0 LASTPIN (-3875 4675) $PN 201
J 0
(-3865 4685);
DISPLAY 0.680851 (-3865 4685);
PAINT MONO (-3865 4685);
FORCEPROP 0 LASTPIN (-3875 3575) $PN 94
J 0
(-3865 3585);
DISPLAY 0.680851 (-3865 3585);
PAINT MONO (-3865 3585);
FORCEPROP 0 LASTPIN (-3875 3625) $PN 93
J 0
(-3865 3635);
DISPLAY 0.680851 (-3865 3635);
PAINT MONO (-3865 3635);
FORCEPROP 2 LAST PART_TYPE SMLF
J 0
(-5075 5100);
DISPLAY 1.021277 (-5075 5100);
FORCEPROP 2 LAST VALUE SCONN288_DDR506112002KQ
J 0
(-5075 5050);
DISPLAY 0.489362 (-5075 5050);
PAINT SKYBLUE (-5075 5050);
FORCEPROP 1 LAST MATERIAL IO
J 0
(-5225 4850);
DISPLAY 0.468085 (-5225 4850);
PAINT SKYBLUE (-5225 4850);
FORCEPROP 1 LAST CDS_LMAN_SYM_OUTLINE -600,1150,600,-1150
J 0
(-4625 3675);
DISPLAY 0.468085 (-4625 3675);
PAINT GREEN (-4625 3675);
DISPLAY INVISIBLE (-4625 3675);
FORCEPROP 1 LAST NEEDS_NO_SIZE TRUE
J 0
(-4625 3675);
DISPLAY 0.723404 (-4625 3675);
PAINT GREEN (-4625 3675);
DISPLAY INVISIBLE (-4625 3675);
FORCEPROP 2 LAST CDS_LIB pure_quanta
J 0
(-4625 3675);
DISPLAY INVISIBLE (-4625 3675);
FORCEPROP 1 LAST PATH I410
J 0
(-4625 3675);
DISPLAY 0.723404 (-4625 3675);
PAINT GREEN (-4625 3675);
DISPLAY INVISIBLE (-4625 3675);
FORCEPROP 1 LAST PART_NUMBER DFHST8FS479
J 0
(-5225 4925);
DISPLAY 0.468085 (-5225 4925);
PAINT SKYBLUE (-5225 4925);
DISPLAY INVISIBLE (-5225 4925);
FORCEADD GND..1
(-2975 5700);
FORCEPROP 3 LASTPIN (-2975 5750) SIG_NAME GND\g
J 0
(-2965 5760);
DISPLAY 0.659574 (-2965 5760);
PAINT MONO (-2965 5760);
DISPLAY INVISIBLE (-2965 5760);
FORCEPROP 2 LAST CDS_LIB pure_quanta_power
J 0
(-2975 5700);
DISPLAY INVISIBLE (-2975 5700);
FORCEPROP 2 LAST BOM_COST MEM
J 0
(-2950 5825);
DISPLAY 0.659574 (-2950 5825);
DISPLAY INVISIBLE (-2950 5825);
FORCEPROP 1 LAST SIZE 1B
J 0
(-2900 5650);
DISPLAY 0.723404 (-2900 5650);
PAINT GREEN (-2900 5650);
DISPLAY INVISIBLE (-2900 5650);
FORCEPROP 2 LAST ROOM MEM_EFGH_DECOUPLING_CAPS
J 0
(-2950 5775);
DISPLAY 0.659574 (-2950 5775);
PAINT RED (-2950 5775);
DISPLAY INVISIBLE (-2950 5775);
FORCEPROP 1 LAST HDL_POWER GND
J 0
(-2975 5850);
DISPLAY 0.723404 (-2975 5850);
PAINT GREEN (-2975 5850);
DISPLAY INVISIBLE (-2975 5850);
FORCEPROP 1 LAST PATH I411
J 0
(-2900 5700);
DISPLAY 0.872340 (-2900 5700);
PAINT AQUA (-2900 5700);
DISPLAY INVISIBLE (-2900 5700);
FORCEADD Q_CAP..1
R 2
(-2975 6050);
FORCEPROP 1 LAST LOCATION C151
J 2
(-3025 6150);
DISPLAY 0.489362 (-3025 6150);
PAINT SKYBLUE (-3025 6150);
FORCEPROP 0 LAST $SEC 1
J 0
(-3025 6200);
DISPLAY 0.680851 (-3025 6200);
PAINT MONO (-3025 6200);
DISPLAY INVISIBLE (-3025 6200);
FORCEPROP 0 LAST CDS_SEC 1
J 0
(-3025 6200);
DISPLAY 0.680851 (-3025 6200);
DISPLAY INVISIBLE (-3025 6200);
FORCEPROP 1 LASTPIN (-2975 6150) $PN 1
J 2
(-2985 6130);
DISPLAY 0.489362 (-2985 6130);
PAINT MONO (-2985 6130);
FORCEPROP 1 LASTPIN (-2975 5950) $PN 2
J 2
(-2985 5930);
DISPLAY 0.489362 (-2985 5930);
PAINT MONO (-2985 5930);
FORCEPROP 1 LAST VOLTAGE 25V
J 2
(-3025 6050);
DISPLAY 0.489362 (-3025 6050);
PAINT SKYBLUE (-3025 6050);
FORCEPROP 1 LAST VALUE 10UF
J 2
(-3025 6100);
DISPLAY 0.489362 (-3025 6100);
PAINT SKYBLUE (-3025 6100);
FORCEPROP 1 LAST MATERIAL X6S
J 2
(-3025 5950);
DISPLAY 0.489362 (-3025 5950);
PAINT SKYBLUE (-3025 5950);
FORCEPROP 1 LAST PACK_TYPE C0805
J 2
(-3025 5850);
DISPLAY 0.489362 (-3025 5850);
PAINT SKYBLUE (-3025 5850);
FORCEPROP 1 LAST TOLERANCE 10%
J 2
(-3025 6000);
DISPLAY 0.489362 (-3025 6000);
PAINT SKYBLUE (-3025 6000);
FORCEPROP 2 LAST CDS_LIB pure_quanta
J 0
(-2975 6050);
DISPLAY INVISIBLE (-2975 6050);
FORCEPROP 0 LAST BOM_COST MEM
J 2
(-3030 6195);
DISPLAY 0.595745 (-3030 6195);
PAINT MONO (-3030 6195);
DISPLAY INVISIBLE (-3030 6195);
FORCEPROP 2 LAST ROOM 
J 2
(-3030 6195);
DISPLAY 0.595745 (-3030 6195);
PAINT RED (-3030 6195);
DISPLAY INVISIBLE (-3030 6195);
FORCEPROP 1 LAST PATH I412
J 2
(-3025 6200);
DISPLAY 0.978723 (-3025 6200);
PAINT WHITE (-3025 6200);
DISPLAY INVISIBLE (-3025 6200);
FORCEPROP 1 LAST PART_NUMBER CH6104KEA00
J 2
(-3025 5900);
DISPLAY 0.489362 (-3025 5900);
PAINT SKYBLUE (-3025 5900);
DISPLAY INVISIBLE (-3025 5900);
FORCEADD Q_CAP..1
R 2
(-2400 6050);
FORCEPROP 1 LAST LOCATION C153
J 2
(-2450 6150);
DISPLAY 0.489362 (-2450 6150);
PAINT SKYBLUE (-2450 6150);
FORCEPROP 0 LAST $SEC 1
J 0
(-2450 6200);
DISPLAY 0.680851 (-2450 6200);
PAINT MONO (-2450 6200);
DISPLAY INVISIBLE (-2450 6200);
FORCEPROP 0 LAST CDS_SEC 1
J 0
(-2450 6200);
DISPLAY 0.680851 (-2450 6200);
DISPLAY INVISIBLE (-2450 6200);
FORCEPROP 1 LASTPIN (-2400 6150) $PN 1
J 2
(-2410 6130);
DISPLAY 0.489362 (-2410 6130);
PAINT MONO (-2410 6130);
FORCEPROP 1 LASTPIN (-2400 5950) $PN 2
J 2
(-2410 5930);
DISPLAY 0.489362 (-2410 5930);
PAINT MONO (-2410 5930);
FORCEPROP 1 LAST VALUE 10UF
J 2
(-2450 6100);
DISPLAY 0.489362 (-2450 6100);
PAINT SKYBLUE (-2450 6100);
FORCEPROP 1 LAST PACK_TYPE C0805
J 2
(-2450 5850);
DISPLAY 0.489362 (-2450 5850);
PAINT SKYBLUE (-2450 5850);
FORCEPROP 1 LAST VOLTAGE 25V
J 2
(-2450 6050);
DISPLAY 0.489362 (-2450 6050);
PAINT SKYBLUE (-2450 6050);
FORCEPROP 1 LAST TOLERANCE 10%
J 2
(-2450 6000);
DISPLAY 0.489362 (-2450 6000);
PAINT SKYBLUE (-2450 6000);
FORCEPROP 1 LAST MATERIAL X6S
J 2
(-2450 5950);
DISPLAY 0.489362 (-2450 5950);
PAINT SKYBLUE (-2450 5950);
FORCEPROP 2 LAST CDS_LIB pure_quanta
J 0
(-2400 6050);
DISPLAY INVISIBLE (-2400 6050);
FORCEPROP 0 LAST BOM_COST MEM
J 2
(-2455 6195);
DISPLAY 0.595745 (-2455 6195);
PAINT MONO (-2455 6195);
DISPLAY INVISIBLE (-2455 6195);
FORCEPROP 2 LAST ROOM 
J 2
(-2455 6195);
DISPLAY 0.595745 (-2455 6195);
PAINT RED (-2455 6195);
DISPLAY INVISIBLE (-2455 6195);
FORCEPROP 1 LAST PATH I413
J 2
(-2450 6200);
DISPLAY 0.978723 (-2450 6200);
PAINT WHITE (-2450 6200);
DISPLAY INVISIBLE (-2450 6200);
FORCEPROP 1 LAST PART_NUMBER CH6104KEA00
J 2
(-2450 5900);
DISPLAY 0.489362 (-2450 5900);
PAINT SKYBLUE (-2450 5900);
DISPLAY INVISIBLE (-2450 5900);
FORCEADD UNIVERSAL_POWER..1
(-2975 6375);
FORCEPROP 3 LASTPIN (-2975 6325) SIG_NAME P12V_MEM_CPU0\g
J 0
(-2965 6335);
DISPLAY 0.659574 (-2965 6335);
PAINT MONO (-2965 6335);
DISPLAY INVISIBLE (-2965 6335);
FORCEPROP 1 LAST HDL_POWER P12V_MEM_CPU0
J 1
(-3000 6425);
DISPLAY 0.489362 (-3000 6425);
PAINT GREEN (-3000 6425);
FORCEPROP 2 LAST BOM_COST VR_SYSTEM
J 0
(-2975 6475);
DISPLAY 0.617021 (-2975 6475);
PAINT PURPLE (-2975 6475);
DISPLAY INVISIBLE (-2975 6475);
FORCEPROP 2 LAST CDS_LIB pure_quanta_power
J 0
(-2975 6375);
DISPLAY INVISIBLE (-2975 6375);
FORCEPROP 1 LAST PATH I414
J 0
(-2925 6400);
DISPLAY 0.872340 (-2925 6400);
PAINT AQUA (-2925 6400);
DISPLAY INVISIBLE (-2925 6400);
FORCEADD OFFPAGE..1
(-8675 2825);
FORCEPROP 2 LAST $XR5 91 
J 0
(-9377 2825);
DISPLAY 0.638298 (-9377 2825);
PAINT MONO (-9377 2825);
FORCEPROP 2 LAST $XR4 89 
J 0
(-9287 2825);
DISPLAY 0.638298 (-9287 2825);
PAINT MONO (-9287 2825);
FORCEPROP 2 LAST $XR3 88 
J 0
(-9197 2825);
DISPLAY 0.638298 (-9197 2825);
PAINT MONO (-9197 2825);
FORCEPROP 2 LAST $XR2 87 
J 0
(-9107 2825);
DISPLAY 0.638298 (-9107 2825);
PAINT MONO (-9107 2825);
FORCEPROP 2 LAST $XR1 86 
J 0
(-9017 2825);
DISPLAY 0.638298 (-9017 2825);
PAINT MONO (-9017 2825);
FORCEPROP 2 LAST $XR0 159 
J 0
(-8927 2825);
DISPLAY 0.638298 (-8927 2825);
PAINT MONO (-8927 2825);
FORCEPROP 2 LAST CDS_LIB mstr_standard
J 0
(-8675 2825);
DISPLAY 0.808511 (-8675 2825);
DISPLAY INVISIBLE (-8675 2825);
FORCEPROP 1 LAST OFFPAGE TRUE
J 0
(-8350 2700);
DISPLAY 0.872340 (-8350 2700);
PAINT GREEN (-8350 2700);
DISPLAY INVISIBLE (-8350 2700);
FORCEPROP 1 LAST COMMENT_BODY TRUE
J 0
(-8550 2725);
DISPLAY 0.872340 (-8550 2725);
PAINT GREEN (-8550 2725);
DISPLAY INVISIBLE (-8550 2725);
FORCEPROP 2 LAST PATH I415
J 0
(-8950 2875);
DISPLAY 0.680851 (-8950 2875);
DISPLAY INVISIBLE (-8950 2875);
FORCEADD Q_RES..1
(-8025 2825);
FORCEPROP 1 LAST LOCATION R1572
J 0
(-8075 2850);
DISPLAY 0.510638 (-8075 2850);
PAINT SKYBLUE (-8075 2850);
FORCEPROP 0 LAST $SEC 1
J 0
(-8075 2925);
DISPLAY 0.680851 (-8075 2925);
PAINT MONO (-8075 2925);
DISPLAY INVISIBLE (-8075 2925);
FORCEPROP 0 LAST CDS_SEC 1
J 0
(-8075 2925);
DISPLAY 0.680851 (-8075 2925);
DISPLAY INVISIBLE (-8075 2925);
FORCEPROP 1 LASTPIN (-8125 2825) $PN 1
J 0
(-8113 2837);
DISPLAY 0.787234 (-8113 2837);
PAINT MONO (-8113 2837);
FORCEPROP 1 LASTPIN (-7925 2825) $PN 2
J 0
(-7963 2837);
DISPLAY 0.787234 (-7963 2837);
PAINT MONO (-7963 2837);
FORCEPROP 1 LAST VALUE 49.9
J 2
(-7900 2875);
DISPLAY 0.510638 (-7900 2875);
PAINT SKYBLUE (-7900 2875);
FORCEPROP 1 LAST TOLERANCE 1%
J 0
(-8025 2725);
DISPLAY 0.978723 (-8025 2725);
DISPLAY INVISIBLE (-8025 2725);
FORCEPROP 1 LAST WATTAGE 1/16W
J 2
(-8050 2675);
DISPLAY 0.978723 (-8050 2675);
DISPLAY INVISIBLE (-8050 2675);
FORCEPROP 1 LAST PACK_TYPE 0402LF
J 0
(-7775 2675);
DISPLAY 0.978723 (-7775 2675);
DISPLAY INVISIBLE (-7775 2675);
FORCEPROP 1 LAST MATERIAL CHIP
J 0
(-8025 2675);
DISPLAY 0.978723 (-8025 2675);
DISPLAY INVISIBLE (-8025 2675);
FORCEPROP 2 LAST CDS_LIB pure_quanta
J 0
(-8025 2825);
DISPLAY INVISIBLE (-8025 2825);
FORCEPROP 1 LAST PATH I416
J 0
(-8075 2975);
DISPLAY 0.978723 (-8075 2975);
PAINT WHITE (-8075 2975);
DISPLAY INVISIBLE (-8075 2975);
FORCEPROP 1 LAST PART_NUMBER CS04992FB07
J 0
(-8075 2925);
DISPLAY 0.978723 (-8075 2925);
DISPLAY INVISIBLE (-8075 2925);
FORCEADD OFFPAGE..6
(-8900 2925);
FORCEPROP 2 LAST $XR5 159 
J 0
(-9269 2889);
DISPLAY 0.638298 (-9269 2889);
PAINT MONO (-9269 2889);
FORCEPROP 2 LAST $XR4 91 
J 0
(-9149 2889);
DISPLAY 0.638298 (-9149 2889);
PAINT MONO (-9149 2889);
FORCEPROP 2 LAST $XR3 89 
J 0
(-9419 2925);
DISPLAY 0.638298 (-9419 2925);
PAINT MONO (-9419 2925);
FORCEPROP 2 LAST $XR2 88 
J 0
(-9329 2925);
DISPLAY 0.638298 (-9329 2925);
PAINT MONO (-9329 2925);
FORCEPROP 2 LAST $XR1 87 
J 0
(-9239 2925);
DISPLAY 0.638298 (-9239 2925);
PAINT MONO (-9239 2925);
FORCEPROP 2 LAST $XR0 86 
J 0
(-9149 2925);
DISPLAY 0.638298 (-9149 2925);
PAINT MONO (-9149 2925);
FORCEPROP 2 LAST CDS_LIB mstr_standard
J 0
(-8900 2925);
DISPLAY 0.808511 (-8900 2925);
DISPLAY INVISIBLE (-8900 2925);
FORCEPROP 1 LAST OFFPAGE TRUE
J 0
(-8575 2800);
DISPLAY 0.872340 (-8575 2800);
PAINT GREEN (-8575 2800);
DISPLAY INVISIBLE (-8575 2800);
FORCEPROP 1 LAST COMMENT_BODY TRUE
J 0
(-8800 2850);
DISPLAY 0.872340 (-8800 2850);
PAINT GREEN (-8800 2850);
DISPLAY INVISIBLE (-8800 2850);
FORCEPROP 2 LAST PATH I417
J 0
(-9175 2975);
DISPLAY 0.680851 (-9175 2975);
DISPLAY INVISIBLE (-9175 2975);
FORCEADD Q_RES..1
(-8325 3025);
FORCEPROP 1 LAST LOCATION R1678
J 0
(-8500 3025);
DISPLAY 0.510638 (-8500 3025);
FORCEPROP 0 LAST $SEC 1
J 0
(-8475 3075);
DISPLAY 0.680851 (-8475 3075);
PAINT MONO (-8475 3075);
DISPLAY INVISIBLE (-8475 3075);
FORCEPROP 0 LAST CDS_SEC 1
J 0
(-8475 3075);
DISPLAY 0.680851 (-8475 3075);
DISPLAY INVISIBLE (-8475 3075);
FORCEPROP 1 LASTPIN (-8425 3025) $PN 1
J 0
(-8413 3037);
DISPLAY 0.787234 (-8413 3037);
PAINT MONO (-8413 3037);
FORCEPROP 1 LASTPIN (-8225 3025) $PN 2
J 0
(-8263 3037);
DISPLAY 0.787234 (-8263 3037);
PAINT MONO (-8263 3037);
FORCEPROP 1 LAST PACK_TYPE 0402LF
J 0
(-8275 3000);
DISPLAY 0.404255 (-8275 3000);
FORCEPROP 1 LAST MATERIAL CHIP
J 0
(-8425 3000);
DISPLAY 0.404255 (-8425 3000);
FORCEPROP 1 LAST VALUE 10
J 2
(-8175 3025);
DISPLAY 0.404255 (-8175 3025);
FORCEPROP 1 LAST TOLERANCE 1%
J 0
(-8325 2925);
DISPLAY 0.978723 (-8325 2925);
DISPLAY INVISIBLE (-8325 2925);
FORCEPROP 1 LAST WATTAGE 1/16W
J 2
(-8350 2875);
DISPLAY 0.978723 (-8350 2875);
DISPLAY INVISIBLE (-8350 2875);
FORCEPROP 2 LAST CDS_LIB pure_quanta
J 0
(-8325 3025);
DISPLAY INVISIBLE (-8325 3025);
FORCEPROP 1 LAST PATH I418
J 0
(-8375 3175);
DISPLAY 0.978723 (-8375 3175);
PAINT WHITE (-8375 3175);
DISPLAY INVISIBLE (-8375 3175);
FORCEPROP 1 LAST PART_NUMBER CS01002FB07
J 0
(-8375 3125);
DISPLAY 0.978723 (-8375 3125);
DISPLAY INVISIBLE (-8375 3125);
FORCEADD QUANTA_TITLE_BLOCK_C..1
(-100 100);
FORCEPROP 0 LAST CDS_CON_LAST_MODIFIED Thu Sep 14 16:12:06 2023
J 0
(-1985 115);
DISPLAY INVISIBLE (-1985 115);
FORCEPROP 1 LAST CUSTOM_TXT_CDS <CON_LAST_MODIFIED>
J 0
(-1985 115);
DISPLAY 0.978723 (-1985 115);
FORCEPROP 2 LAST CUSTOM_TXT_CDS <XR_PAGE_TITLE>
J 0
(-7990 5350);
DISPLAY 0.638298 (-7990 5350);
PAINT PINK (-7990 5350);
DISPLAY INVISIBLE (-7990 5350);
FORCEPROP 1 LAST CUSTOM_TXT_CDS <NAME_2>
J 0
(-3275 150);
FORCEPROP 1 LAST CUSTOM_TXT_CDS <NAME_1>
J 0
(-3275 275);
FORCEPROP 1 LAST CUSTOM_TXT_CDS <Q_NUMBER>
J 0
(-1503 203);
DISPLAY 1.212766 (-1503 203);
FORCEPROP 1 LAST CUSTOM_TXT_CDS <Q_PROJ>
J 0
(-2482 202);
DISPLAY 1.212766 (-2482 202);
FORCEPROP 1 LAST CUSTOM_TXT_CDS <Q_REV>
J 0
(-284 203);
DISPLAY 1.212766 (-284 203);
FORCEPROP 1 LAST CUSTOM_TXT_CDS <CON_PAGE_NUM> OF <CON_TOTAL_PAGES>
J 0
(-546 118);
DISPLAY 0.978723 (-546 118);
FORCEPROP 1 LAST Q_TITLE DDR5 - CPU0 CHE
J 0
(-9425 150);
DISPLAY 2.446809 (-9425 150);
PAINT GREEN (-9425 150);
FORCEPROP 2 LAST PAGE_BORDER TRUE
J 0
(-7990 5350);
DISPLAY 0.638298 (-7990 5350);
PAINT PINK (-7990 5350);
DISPLAY INVISIBLE (-7990 5350);
FORCEPROP 1 LAST CDS_LMAN_SYM_OUTLINE -9475,6775,100,-125
J 0
(-100 100);
DISPLAY 0.468085 (-100 100);
PAINT GREEN (-100 100);
DISPLAY INVISIBLE (-100 100);
FORCEPROP 2 LAST CDS_LIB pure_quanta
J 0
(-100 100);
DISPLAY INVISIBLE (-100 100);
FORCEPROP 2 LAST CDS_XR_PAGE_TITLE CR-90 : @T6G_MB_LIB.T6G(SCH_1):PAGE90
J 0
(-7990 5350);
DISPLAY 0.638298 (-7990 5350);
PAINT PINK (-7990 5350);
DISPLAY INVISIBLE (-7990 5350);
FORCEPROP 1 LAST Q_DEPT BU9
J 1
(-3863 149);
DISPLAY 1.957447 (-3863 149);
PAINT GREEN (-3863 149);
DISPLAY INVISIBLE (-3863 149);
FORCEPROP 1 LAST COMMENT_BODY TRUE
J 0
(-88 87);
DISPLAY 0.978723 (-88 87);
PAINT GREEN (-88 87);
DISPLAY INVISIBLE (-88 87);
FORCEADD DNS..2
(-8575 2475);
PAINT RED (-8575 2475);
FORCEPROP 2 LAST CDS_LIB mstr_misc
J 0
(-8575 2475);
DISPLAY INVISIBLE (-8575 2475);
FORCEPROP 1 LAST COMMENT_BODY TRUE
R 1
J 0
(-8500 2250);
DISPLAY 0.872340 (-8500 2250);
PAINT PEACH (-8500 2250);
DISPLAY INVISIBLE (-8500 2250);
WIRE 17 -1 (-6225 3300)(-6225 3250);
WIRE 17 -1 (-6225 3350)(-6225 3300);
WIRE 17 -1 (-6225 3250)(-6225 3200);
WIRE 17 -1 (-6225 3150)(-6225 3200);
WIRE 17 -1 (-6225 3400)(-6225 3350);
WIRE 17 -1 (-6225 3450)(-6225 3400);
WIRE 17 -1 (-6225 3100)(-6225 3150);
WIRE 17 -1 (-6225 3050)(-6225 3100);
WIRE 17 -1 (-6225 3500)(-6225 3450);
WIRE 17 -1 (-6225 3550)(-6225 3500);
WIRE 17 -1 (-6225 3000)(-6225 3050);
WIRE 17 -1 (-6225 3000)(-6225 2950);
WIRE 17 -1 (-6225 3600)(-6225 3550);
WIRE 17 -1 (-6225 3650)(-6225 3600);
WIRE 17 -1 (-6225 2950)(-6225 2900);
WIRE 17 -1 (-6225 2900)(-6225 2850);
WIRE 17 -1 (-6225 3700)(-6225 3650);
WIRE 17 -1 (-6225 3750)(-6225 3700);
WIRE 17 -1 (-6225 2850)(-6225 2800);
WIRE 17 -1 (-6225 2800)(-6225 2750);
WIRE 17 -1 (-6225 3800)(-6225 3750);
WIRE 17 -1 (-6225 3850)(-6225 3800);
WIRE 17 -1 (-6225 2750)(-6225 2700);
WIRE 17 -1 (-6225 2700)(-6225 2650);
WIRE 17 -1 (-6225 3900)(-6225 3850);
WIRE 17 -1 (-6225 3950)(-6225 3900);
WIRE 17 -1 (-6225 2650)(-6225 2600);
WIRE 17 -1 (-6225 2550)(-6225 2600);
WIRE 17 -1 (-6225 4000)(-6225 3950);
WIRE 17 -1 (-6225 4000)(-5675 4000);
FORCEPROP 2 LAST SIG_NAME M_E_CPU0_SB_DQ<31:0>
J 0
(-6160 4010);
DISPLAY 0.489362 (-6160 4010);
WIRE 17 -1 (-3425 4550)(-3425 4450);
WIRE 17 -1 (-3425 4650)(-3425 4550);
WIRE 17 -1 (-3425 4450)(-3425 4350);
WIRE 17 -1 (-3425 4350)(-3425 4250);
WIRE 17 -1 (-3425 4675)(-3425 4650);
WIRE 17 -1 (-3425 4675)(-2725 4675);
FORCEPROP 2 LAST SIG_NAME M_E_CPU0_SA_DQS_DN<9:0>
J 0
(-3360 4685);
DISPLAY 0.489362 (-3360 4685);
WIRE 17 -1 (-3625 4700)(-3625 4600);
WIRE 17 -1 (-3625 4725)(-3625 4700);
WIRE 17 -1 (-3625 4600)(-3625 4500);
WIRE 17 -1 (-3625 4500)(-3625 4400);
WIRE 17 -1 (-3625 4725)(-2725 4725);
FORCEPROP 2 LAST SIG_NAME M_E_CPU0_SA_DQS_DP<9:0>
J 0
(-3360 4735);
DISPLAY 0.489362 (-3360 4735);
WIRE 17 -1 (-6225 4950)(-6225 4900);
WIRE 17 -1 (-6225 5000)(-6225 4950);
WIRE 17 -1 (-6225 4900)(-6225 4850);
WIRE 17 -1 (-6225 4800)(-6225 4850);
WIRE 17 -1 (-6225 5050)(-6225 5000);
WIRE 17 -1 (-6225 5100)(-6225 5050);
WIRE 17 -1 (-6225 4750)(-6225 4800);
WIRE 17 -1 (-6225 4700)(-6225 4750);
WIRE 17 -1 (-6225 5150)(-6225 5100);
WIRE 17 -1 (-6225 5200)(-6225 5150);
WIRE 17 -1 (-6225 4650)(-6225 4700);
WIRE 17 -1 (-6225 4650)(-6225 4600);
WIRE 17 -1 (-6225 5250)(-6225 5200);
WIRE 17 -1 (-6225 5300)(-6225 5250);
WIRE 17 -1 (-6225 4600)(-6225 4550);
WIRE 17 -1 (-6225 4550)(-6225 4500);
WIRE 17 -1 (-6225 5350)(-6225 5300);
WIRE 17 -1 (-6225 5400)(-6225 5350);
WIRE 17 -1 (-6225 4500)(-6225 4450);
WIRE 17 -1 (-6225 4450)(-6225 4400);
WIRE 17 -1 (-6225 5450)(-6225 5400);
WIRE 17 -1 (-6225 5500)(-6225 5450);
WIRE 17 -1 (-6225 4400)(-6225 4350);
WIRE 17 -1 (-6225 4350)(-6225 4300);
WIRE 17 -1 (-6225 5550)(-6225 5500);
WIRE 17 -1 (-6225 5600)(-6225 5550);
WIRE 17 -1 (-6225 4300)(-6225 4250);
WIRE 17 -1 (-6225 4200)(-6225 4250);
WIRE 17 -1 (-6225 5650)(-6225 5600);
WIRE 17 -1 (-6225 5650)(-5675 5650);
FORCEPROP 2 LAST SIG_NAME M_E_CPU0_SA_DQ<31:0>
J 0
(-6160 5660);
DISPLAY 0.489362 (-6160 5660);
WIRE 17 -1 (-6225 4150)(-6225 4200);
WIRE 17 -1 (-6225 4100)(-6225 4150);
WIRE 17 -1 (-6225 4050)(-6225 4100);
WIRE 17 -1 (-3425 3850)(-3425 3750);
WIRE 17 -1 (-3425 3950)(-3425 3850);
WIRE 17 -1 (-3425 3950)(-3425 4050);
WIRE 17 -1 (-3425 4050)(-3425 4150);
WIRE 17 -1 (-3425 4150)(-3425 4250);
WIRE 17 -1 (-3625 3675)(-3625 3650);
WIRE 17 -1 (-3625 3675)(-2725 3675);
FORCEPROP 2 LAST SIG_NAME M_E_CPU0_SB_DQS_DP<9:0>
J 0
(-3360 3685);
DISPLAY 0.489362 (-3360 3685);
WIRE 17 -1 (-3425 3625)(-3425 3600);
WIRE 17 -1 (-3425 3625)(-2725 3625);
FORCEPROP 2 LAST SIG_NAME M_E_CPU0_SB_DQS_DN<9:0>
J 0
(-3360 3635);
DISPLAY 0.489362 (-3360 3635);
WIRE 17 -1 (-3425 3500)(-3425 3400);
WIRE 17 -1 (-3425 3600)(-3425 3500);
WIRE 17 -1 (-3425 3400)(-3425 3300);
WIRE 17 -1 (-3425 3300)(-3425 3200);
WIRE 17 -1 (-3625 4000)(-3625 3900);
WIRE 17 -1 (-3625 4000)(-3625 4100);
WIRE 17 -1 (-3625 3900)(-3625 3800);
WIRE 17 -1 (-3625 4100)(-3625 4200);
WIRE 17 -1 (-3625 4200)(-3625 4300);
WIRE 17 -1 (-3625 4400)(-3625 4300);
WIRE 17 -1 (-6225 2500)(-6225 2550);
WIRE 17 -1 (-6225 2450)(-6225 2500);
WIRE 17 -1 (-6225 2400)(-6225 2450);
WIRE 17 -1 (-8025 4100)(-8025 4150);
WIRE 17 -1 (-8025 4100)(-8025 4050);
WIRE 17 -1 (-8025 4200)(-8025 4150);
WIRE 17 -1 (-8025 4200)(-8025 4225);
WIRE 17 -1 (-8025 4000)(-8025 4050);
WIRE 17 -1 (-8025 3950)(-8025 4000);
WIRE 17 -1 (-8025 4225)(-8525 4225);
FORCEPROP 2 LAST SIG_NAME M_E_CPU0_SA_CB<7:0>
J 0
(-8475 4235);
DISPLAY 0.489362 (-8475 4235);
WIRE 17 -1 (-3625 3450)(-3625 3350);
WIRE 17 -1 (-3625 3550)(-3625 3450);
WIRE 17 -1 (-3625 3350)(-3625 3250);
WIRE 17 -1 (-3625 3150)(-3625 3250);
WIRE 17 -1 (-3625 3650)(-3625 3550);
WIRE 17 -1 (-3625 3050)(-3625 3150);
WIRE 17 -1 (-3625 2950)(-3625 3050);
WIRE 17 -1 (-3425 3100)(-3425 3200);
WIRE 17 -1 (-3425 3000)(-3425 3100);
WIRE 17 -1 (-3425 2900)(-3425 3000);
WIRE 17 -1 (-3625 2950)(-3625 2850);
WIRE 17 -1 (-3425 2900)(-3425 2800);
WIRE 17 -1 (-3625 2850)(-3625 2750);
WIRE 17 -1 (-3425 2800)(-3425 2700);
WIRE 17 -1 (-8025 5100)(-8025 5150);
WIRE 17 -1 (-8025 5050)(-8025 5100);
WIRE 17 -1 (-8025 5150)(-8025 5200);
WIRE 17 -1 (-8025 5200)(-8025 5225);
WIRE 17 -1 (-8025 5000)(-8025 5050);
WIRE 17 -1 (-8025 4950)(-8025 5000);
WIRE 17 -1 (-8025 5225)(-8525 5225);
FORCEPROP 2 LAST SIG_NAME M_E_CPU0_SB_CA<6:0>
J 0
(-8510 5235);
DISPLAY 0.489362 (-8510 5235);
WIRE 17 -1 (-8025 5350)(-8025 5400);
WIRE 17 -1 (-8025 5300)(-8025 5350);
WIRE 17 -1 (-8025 5400)(-8025 5450);
WIRE 17 -1 (-8025 5450)(-8025 5500);
WIRE 17 -1 (-8025 5500)(-8025 5550);
WIRE 17 -1 (-8025 5550)(-8025 5600);
WIRE 17 -1 (-8025 5600)(-8025 5625);
WIRE 17 -1 (-8025 5625)(-8525 5625);
FORCEPROP 2 LAST SIG_NAME M_E_CPU0_SA_CA<6:0>
J 0
(-8510 5635);
DISPLAY 0.489362 (-8510 5635);
WIRE 17 -1 (-8025 3400)(-8025 3450);
WIRE 17 -1 (-8025 3450)(-8025 3500);
WIRE 17 -1 (-8025 3500)(-8025 3550);
WIRE 17 -1 (-8025 3550)(-8025 3600);
WIRE 17 -1 (-8025 3650)(-8025 3600);
WIRE 17 -1 (-8025 3650)(-8025 3700);
WIRE 17 -1 (-8025 3750)(-8025 3700);
WIRE 17 -1 (-8025 3750)(-8025 3775);
WIRE 17 -1 (-8025 3775)(-8525 3775);
FORCEPROP 2 LAST SIG_NAME M_E_CPU0_SB_CB<7:0>
J 0
(-8475 3785);
DISPLAY 0.489362 (-8475 3785);
WIRE 17 -1 (-8025 3850)(-8025 3900);
WIRE 17 -1 (-8025 3900)(-8025 3950);
WIRE 17 -1 (-8025 4900)(-8025 4950);
WIRE 16 -1 (-6650 1250)(-6650 1325);
WIRE 16 -1 (-8875 3225)(-8875 3300);
WIRE 16 -1 (-8600 2575)(-8600 2600);
WIRE 16 -1 (-7725 3075)(-8525 3075);
FORCEPROP 2 LAST SIG_NAME PD_CHE_CPU0_DIMM_SAA
J 0
(-8500 3085);
DISPLAY 0.489362 (-8500 3085);
WIRE 16 -1 (-8875 3500)(-8875 3525);
WIRE 16 -1 (-8875 3525)(-8775 3525);
WIRE 16 -1 (-8775 3125)(-8775 3525);
WIRE 16 -1 (-8775 3525)(-8775 3600);
WIRE 16 -1 (-8775 3125)(-7725 3125);
WIRE 16 -1 (-7775 2825)(-7925 2825);
WIRE 16 -1 (-7775 2975)(-7775 2825);
WIRE 16 -1 (-7725 2975)(-7775 2975);
FORCEPROP 2 LAST SIG_NAME I3C_SPD_DDRE_CPU0_SCL
J 0
(-8135 2925);
DISPLAY 0.361702 (-8135 2925);
FORCEPROP 2 LASTPROP $XRERR UNIQUE?
J 0
(-8375 2925);
DISPLAY 0.638298 (-8375 2925);
PAINT MONO (-8375 2925);
DISPLAY INVISIBLE (-8375 2925);
WIRE 16 -1 (-7725 3025)(-8225 3025);
FORCEPROP 2 LAST SIG_NAME I3C_SPD_DDRE_CPU0_SDA
J 0
(-8135 3035);
DISPLAY 0.382979 (-8135 3035);
FORCEPROP 2 LASTPROP $XRERR UNIQUE?
J 0
(-8375 3035);
DISPLAY 0.638298 (-8375 3035);
PAINT MONO (-8375 3035);
DISPLAY INVISIBLE (-8375 3035);
WIRE 16 -1 (-8125 2825)(-8625 2825);
FORCEPROP 2 LAST SIG_NAME I3C_SPD_DDRAF_CPU0_SCL
J 0
(-8685 2835);
DISPLAY 0.489362 (-8685 2835);
WIRE 16 -1 (-7725 2725)(-8400 2725);
FORCEPROP 2 LAST SIG_NAME PWRGD_CHE_CPU0_DIMM
J 0
(-8285 2735);
DISPLAY 0.489362 (-8285 2735);
FORCEPROP 2 LASTPROP $XRERR UNIQUE?
J 0
(-8525 2735);
DISPLAY 0.638298 (-8525 2735);
PAINT MONO (-8525 2735);
DISPLAY INVISIBLE (-8525 2735);
WIRE 16 -1 (-8400 2325)(-8400 2725);
WIRE 16 -1 (-8400 2325)(-8600 2325);
WIRE 16 -1 (-8600 2325)(-8625 2325);
WIRE 16 -1 (-8600 2375)(-8600 2325);
WIRE 16 -1 (-8450 2925)(-8450 3025);
WIRE 16 -1 (-8450 2925)(-8850 2925);
FORCEPROP 2 LAST SIG_NAME I3C_SPD_DDRAF_CPU0_SDA
J 0
(-8860 2935);
DISPLAY 0.382979 (-8860 2935);
WIRE 16 -1 (-8450 3025)(-8425 3025);
WIRE 16 -1 (-7725 3225)(-8375 3225);
FORCEPROP 2 LAST SIG_NAME M_E_CPU0_ALERT_N
J 0
(-8360 3235);
DISPLAY 0.489362 (-8360 3235);
WIRE 16 -1 (-6525 5575)(-6325 5575);
WIRE 16 -1 (-7725 4175)(-7925 4175);
WIRE 16 -1 (-7725 4025)(-7925 4025);
WIRE 16 -1 (-7725 3875)(-7925 3875);
WIRE 16 -1 (-7725 3725)(-7925 3725);
WIRE 16 -1 (-7725 5275)(-7925 5275);
WIRE 16 -1 (-7725 4875)(-7925 4875);
WIRE 16 -1 (-7725 4925)(-7925 4925);
WIRE 16 -1 (-7725 5375)(-7925 5375);
WIRE 16 -1 (-7725 4975)(-7925 4975);
WIRE 16 -1 (-7725 5425)(-7925 5425);
WIRE 16 -1 (-7725 5025)(-7925 5025);
WIRE 16 -1 (-7725 5475)(-7925 5475);
WIRE 16 -1 (-7725 5525)(-7925 5525);
WIRE 16 -1 (-7725 5125)(-7925 5125);
WIRE 16 -1 (-7725 5575)(-7925 5575);
WIRE 16 -1 (-7725 5175)(-7925 5175);
WIRE 16 -1 (-7725 3975)(-7925 3975);
WIRE 16 -1 (-7725 3925)(-7925 3925);
WIRE 16 -1 (-7725 3825)(-7925 3825);
WIRE 16 -1 (-7725 3675)(-7925 3675);
WIRE 16 -1 (-7725 3625)(-7925 3625);
WIRE 16 -1 (-7725 3575)(-7925 3575);
WIRE 16 -1 (-7725 3525)(-7925 3525);
WIRE 16 -1 (-7725 3475)(-7925 3475);
WIRE 16 -1 (-7725 3425)(-7925 3425);
WIRE 16 -1 (-7725 3375)(-7925 3375);
WIRE 16 -1 (-7725 4275)(-8525 4275);
FORCEPROP 2 LAST SIG_NAME M_E_CPU0_CLK_DN<0>
J 0
(-8475 4285);
DISPLAY 0.489362 (-8475 4285);
WIRE 16 -1 (-7725 4425)(-8525 4425);
FORCEPROP 2 LAST SIG_NAME M_E_CPU0_SB_CS_N<0>
J 0
(-8475 4435);
DISPLAY 0.489362 (-8475 4435);
WIRE 16 -1 (-7725 4625)(-8525 4625);
FORCEPROP 2 LAST SIG_NAME M_E_CPU0_SA_CS_N<1>
J 0
(-8475 4635);
DISPLAY 0.489362 (-8475 4635);
WIRE 16 -1 (-7725 4475)(-8525 4475);
FORCEPROP 2 LAST SIG_NAME M_E_CPU0_SB_CS_N<1>
J 0
(-8475 4485);
DISPLAY 0.489362 (-8475 4485);
WIRE 16 -1 (-6325 5525)(-6525 5525);
WIRE 16 -1 (-6325 5425)(-6525 5425);
WIRE 16 -1 (-6525 5375)(-6325 5375);
WIRE 16 -1 (-6325 5325)(-6525 5325);
WIRE 16 -1 (-6325 5225)(-6525 5225);
WIRE 16 -1 (-6525 5175)(-6325 5175);
WIRE 16 -1 (-6325 5075)(-6525 5075);
WIRE 16 -1 (-6325 4925)(-6525 4925);
WIRE 16 -1 (-6325 4825)(-6525 4825);
WIRE 16 -1 (-6525 4775)(-6325 4775);
WIRE 16 -1 (-6325 4725)(-6525 4725);
WIRE 16 -1 (-6325 4625)(-6525 4625);
WIRE 16 -1 (-6525 4575)(-6325 4575);
WIRE 16 -1 (-6325 4525)(-6525 4525);
WIRE 16 -1 (-6325 4475)(-6525 4475);
WIRE 16 -1 (-6325 4425)(-6525 4425);
WIRE 16 -1 (-6525 4375)(-6325 4375);
WIRE 16 -1 (-6325 4325)(-6525 4325);
WIRE 16 -1 (-6325 4275)(-6525 4275);
WIRE 16 -1 (-6325 4225)(-6525 4225);
WIRE 16 -1 (-6525 4175)(-6325 4175);
WIRE 16 -1 (-6325 4125)(-6525 4125);
WIRE 16 -1 (-6325 4075)(-6525 4075);
WIRE 16 -1 (-6325 4025)(-6525 4025);
WIRE 16 -1 (-6525 3925)(-6325 3925);
WIRE 16 -1 (-6325 3875)(-6525 3875);
WIRE 16 -1 (-6325 3825)(-6525 3825);
WIRE 16 -1 (-6325 3775)(-6525 3775);
WIRE 16 -1 (-6525 3725)(-6325 3725);
WIRE 16 -1 (-6325 3675)(-6525 3675);
WIRE 16 -1 (-6325 3625)(-6525 3625);
WIRE 16 -1 (-6325 3575)(-6525 3575);
WIRE 16 -1 (-6525 3525)(-6325 3525);
WIRE 16 -1 (-6325 3475)(-6525 3475);
WIRE 16 -1 (-6325 3425)(-6525 3425);
WIRE 16 -1 (-6325 3375)(-6525 3375);
WIRE 16 -1 (-6525 3325)(-6325 3325);
WIRE 16 -1 (-6325 3275)(-6525 3275);
WIRE 16 -1 (-6325 3175)(-6525 3175);
WIRE 16 -1 (-6525 3125)(-6325 3125);
WIRE 16 -1 (-6325 3075)(-6525 3075);
WIRE 16 -1 (-6325 3025)(-6525 3025);
WIRE 16 -1 (-6325 2975)(-6525 2975);
WIRE 16 -1 (-6525 2925)(-6325 2925);
WIRE 16 -1 (-6325 2875)(-6525 2875);
WIRE 16 -1 (-6325 2775)(-6525 2775);
WIRE 16 -1 (-6525 2725)(-6325 2725);
WIRE 16 -1 (-6325 2675)(-6525 2675);
WIRE 16 -1 (-6325 2625)(-6525 2625);
WIRE 16 -1 (-6325 2575)(-6525 2575);
WIRE 16 -1 (-6525 2525)(-6325 2525);
WIRE 16 -1 (-6325 2475)(-6525 2475);
WIRE 16 -1 (-6325 2425)(-6525 2425);
WIRE 16 -1 (-6325 2375)(-6525 2375);
WIRE 16 -1 (-7725 2175)(-8525 2175);
FORCEPROP 2 LAST SIG_NAME M_E_CPU0_SA_RSP<0>
J 0
(-8475 2185);
DISPLAY 0.489362 (-8475 2185);
WIRE 16 -1 (-7725 2125)(-8525 2125);
FORCEPROP 2 LAST SIG_NAME M_E_CPU0_SB_RSP<0>
J 0
(-8475 2135);
DISPLAY 0.489362 (-8475 2135);
WIRE 16 -1 (-7725 4775)(-8525 4775);
FORCEPROP 2 LAST SIG_NAME M_E_CPU0_SA_PAR
J 0
(-8475 4785);
DISPLAY 0.489362 (-8475 4785);
WIRE 16 -1 (-7725 4725)(-8525 4725);
FORCEPROP 2 LAST SIG_NAME M_E_CPU0_SB_PAR
J 0
(-8475 4735);
DISPLAY 0.489362 (-8475 4735);
WIRE 16 -1 (-6325 5275)(-6525 5275);
WIRE 16 -1 (-6325 5475)(-6525 5475);
WIRE 16 -1 (-7725 5325)(-7925 5325);
WIRE 16 -1 (-7725 5075)(-7925 5075);
WIRE 16 -1 (-6325 5125)(-6525 5125);
WIRE 16 -1 (-3725 4375)(-3875 4375);
WIRE 16 -1 (-3725 3525)(-3875 3525);
WIRE 16 -1 (-3725 3425)(-3875 3425);
WIRE 16 -1 (-3725 3775)(-3875 3775);
WIRE 16 -1 (-3875 2675)(-3525 2675);
WIRE 16 -1 (-3725 2725)(-3875 2725);
WIRE 16 -1 (-3875 3825)(-3525 3825);
WIRE 16 -1 (-3875 2775)(-3525 2775);
WIRE 16 -1 (-3875 2825)(-3725 2825);
WIRE 16 -1 (-3875 3925)(-3525 3925);
WIRE 16 -1 (-3725 3975)(-3875 3975);
WIRE 16 -1 (-3875 2875)(-3525 2875);
WIRE 16 -1 (-3725 2925)(-3875 2925);
WIRE 16 -1 (-3875 4025)(-3525 4025);
WIRE 16 -1 (-3875 2975)(-3525 2975);
WIRE 16 -1 (-3725 3025)(-3875 3025);
WIRE 16 -1 (-3875 4125)(-3525 4125);
WIRE 16 -1 (-3725 4175)(-3875 4175);
WIRE 16 -1 (-3875 3075)(-3525 3075);
WIRE 16 -1 (-3725 3125)(-3875 3125);
WIRE 16 -1 (-3875 4225)(-3525 4225);
WIRE 16 -1 (-3875 4275)(-3725 4275);
WIRE 16 -1 (-3875 3175)(-3525 3175);
WIRE 16 -1 (-3875 3225)(-3725 3225);
WIRE 16 -1 (-3875 4325)(-3525 4325);
WIRE 16 -1 (-3875 3275)(-3525 3275);
WIRE 16 -1 (-3725 3325)(-3875 3325);
WIRE 16 -1 (-3725 4475)(-3875 4475);
WIRE 16 -1 (-6525 4975)(-6325 4975);
WIRE 16 -1 (-3725 4075)(-3875 4075);
WIRE 16 -1 (-7725 4075)(-7925 4075);
WIRE 16 -1 (-7725 4125)(-7925 4125);
WIRE 16 -1 (-7725 4325)(-8525 4325);
FORCEPROP 2 LAST SIG_NAME M_E_CPU0_CLK_DP<0>
J 0
(-8475 4335);
DISPLAY 0.489362 (-8475 4335);
WIRE 16 -1 (-7725 4575)(-8525 4575);
FORCEPROP 2 LAST SIG_NAME M_E_CPU0_SA_CS_N<0>
J 0
(-8475 4585);
DISPLAY 0.489362 (-8475 4585);
WIRE 16 -1 (-6325 5025)(-6525 5025);
WIRE 16 -1 (-6650 1600)(-6650 1525);
WIRE 16 -1 (-6650 1600)(-7375 1600);
FORCEPROP 2 LAST SIG_NAME PD_CHE_CPU0_DIMM_SAA
J 0
(-7360 1610);
DISPLAY 0.489362 (-7360 1610);
WIRE 16 -1 (-9175 2325)(-8825 2325);
FORCEPROP 2 LAST SIG_NAME PWRGD_CHAF_CPU0
J 0
(-9160 2335);
DISPLAY 0.489362 (-9160 2335);
WIRE 16 -1 (-500 2425)(-500 2325);
WIRE 16 -1 (-500 2475)(-500 2425);
WIRE 16 -1 (-500 2425)(-800 2425);
WIRE 16 -1 (-500 2325)(-500 2275);
WIRE 16 -1 (-500 2325)(-800 2325);
WIRE 16 -1 (-500 2275)(-500 2225);
WIRE 16 -1 (-500 2275)(-800 2275);
WIRE 16 -1 (-500 2525)(-500 2475);
WIRE 16 -1 (-500 2475)(-800 2475);
WIRE 16 -1 (-500 2575)(-500 2525);
WIRE 16 -1 (-500 2525)(-800 2525);
WIRE 16 -1 (-500 2225)(-500 2050);
WIRE 16 -1 (-500 2225)(-800 2225);
WIRE 16 -1 (-500 2625)(-500 2575);
WIRE 16 -1 (-500 2575)(-800 2575);
WIRE 16 -1 (-500 2675)(-500 2625);
WIRE 16 -1 (-500 2625)(-800 2625);
WIRE 16 -1 (-500 2725)(-500 2675);
WIRE 16 -1 (-500 2675)(-800 2675);
WIRE 16 -1 (-500 2775)(-500 2725);
WIRE 16 -1 (-500 2725)(-800 2725);
WIRE 16 -1 (-500 2825)(-500 2775);
WIRE 16 -1 (-500 2775)(-800 2775);
WIRE 16 -1 (-500 2875)(-500 2825);
WIRE 16 -1 (-500 2825)(-800 2825);
WIRE 16 -1 (-500 2925)(-500 2875);
WIRE 16 -1 (-500 2875)(-800 2875);
WIRE 16 -1 (-500 2975)(-500 2925);
WIRE 16 -1 (-500 2925)(-800 2925);
WIRE 16 -1 (-500 3025)(-500 2975);
WIRE 16 -1 (-500 2975)(-800 2975);
WIRE 16 -1 (-500 3075)(-500 3025);
WIRE 16 -1 (-500 3025)(-800 3025);
WIRE 16 -1 (-500 3125)(-500 3075);
WIRE 16 -1 (-500 3075)(-800 3075);
WIRE 16 -1 (-500 3175)(-500 3125);
WIRE 16 -1 (-500 3125)(-800 3125);
WIRE 16 -1 (-500 3225)(-500 3175);
WIRE 16 -1 (-500 3175)(-800 3175);
WIRE 16 -1 (-500 3275)(-500 3225);
WIRE 16 -1 (-500 3225)(-800 3225);
WIRE 16 -1 (-500 3325)(-500 3275);
WIRE 16 -1 (-500 3275)(-800 3275);
WIRE 16 -1 (-500 3375)(-500 3325);
WIRE 16 -1 (-500 3325)(-800 3325);
WIRE 16 -1 (-500 3425)(-500 3375);
WIRE 16 -1 (-500 3375)(-800 3375);
WIRE 16 -1 (-500 3475)(-500 3425);
WIRE 16 -1 (-500 3425)(-800 3425);
WIRE 16 -1 (-500 3525)(-500 3475);
WIRE 16 -1 (-500 3475)(-800 3475);
WIRE 16 -1 (-500 3575)(-500 3525);
WIRE 16 -1 (-500 3525)(-800 3525);
WIRE 16 -1 (-500 3625)(-500 3575);
WIRE 16 -1 (-500 3575)(-800 3575);
WIRE 16 -1 (-500 3675)(-500 3625);
WIRE 16 -1 (-500 3625)(-800 3625);
WIRE 16 -1 (-500 3725)(-500 3675);
WIRE 16 -1 (-500 3675)(-800 3675);
WIRE 16 -1 (-500 3775)(-500 3725);
WIRE 16 -1 (-500 3725)(-800 3725);
WIRE 16 -1 (-500 3825)(-500 3775);
WIRE 16 -1 (-500 3775)(-800 3775);
WIRE 16 -1 (-500 3875)(-500 3825);
WIRE 16 -1 (-500 3825)(-800 3825);
WIRE 16 -1 (-500 3925)(-500 3875);
WIRE 16 -1 (-500 3875)(-800 3875);
WIRE 16 -1 (-500 3975)(-500 3925);
WIRE 16 -1 (-500 3925)(-800 3925);
WIRE 16 -1 (-500 4025)(-500 3975);
WIRE 16 -1 (-500 3975)(-800 3975);
WIRE 16 -1 (-500 4075)(-500 4025);
WIRE 16 -1 (-500 4025)(-800 4025);
WIRE 16 -1 (-500 4125)(-500 4075);
WIRE 16 -1 (-500 4075)(-800 4075);
WIRE 16 -1 (-500 4175)(-500 4125);
WIRE 16 -1 (-500 4125)(-800 4125);
WIRE 16 -1 (-500 4225)(-500 4175);
WIRE 16 -1 (-500 4175)(-800 4175);
WIRE 16 -1 (-500 4275)(-500 4225);
WIRE 16 -1 (-500 4225)(-800 4225);
WIRE 16 -1 (-500 4325)(-500 4275);
WIRE 16 -1 (-500 4275)(-800 4275);
WIRE 16 -1 (-500 4375)(-500 4325);
WIRE 16 -1 (-500 4325)(-800 4325);
WIRE 16 -1 (-500 4425)(-500 4375);
WIRE 16 -1 (-500 4375)(-800 4375);
WIRE 16 -1 (-500 4475)(-500 4425);
WIRE 16 -1 (-500 4425)(-800 4425);
WIRE 16 -1 (-500 4525)(-500 4475);
WIRE 16 -1 (-500 4475)(-800 4475);
WIRE 16 -1 (-500 4575)(-500 4525);
WIRE 16 -1 (-500 4525)(-800 4525);
WIRE 16 -1 (-500 4625)(-500 4575);
WIRE 16 -1 (-500 4575)(-800 4575);
WIRE 16 -1 (-500 4675)(-500 4625);
WIRE 16 -1 (-500 4625)(-800 4625);
WIRE 16 -1 (-500 4725)(-500 4675);
WIRE 16 -1 (-500 4675)(-800 4675);
WIRE 16 -1 (-500 4775)(-500 4725);
WIRE 16 -1 (-500 4725)(-800 4725);
WIRE 16 -1 (-500 4825)(-500 4775);
WIRE 16 -1 (-500 4775)(-800 4775);
WIRE 16 -1 (-500 4875)(-500 4825);
WIRE 16 -1 (-500 4825)(-800 4825);
WIRE 16 -1 (-500 4925)(-500 4875);
WIRE 16 -1 (-500 4875)(-800 4875);
WIRE 16 -1 (-500 4975)(-500 4925);
WIRE 16 -1 (-500 4925)(-800 4925);
WIRE 16 -1 (-500 5025)(-500 4975);
WIRE 16 -1 (-500 4975)(-800 4975);
WIRE 16 -1 (-500 5075)(-500 5025);
WIRE 16 -1 (-500 5025)(-800 5025);
WIRE 16 -1 (-500 5125)(-500 5075);
WIRE 16 -1 (-500 5075)(-800 5075);
WIRE 16 -1 (-500 5175)(-500 5125);
WIRE 16 -1 (-500 5125)(-800 5125);
WIRE 16 -1 (-500 5225)(-500 5175);
WIRE 16 -1 (-500 5175)(-800 5175);
WIRE 16 -1 (-500 5275)(-500 5225);
WIRE 16 -1 (-500 5225)(-800 5225);
WIRE 16 -1 (-500 5325)(-500 5275);
WIRE 16 -1 (-500 5275)(-800 5275);
WIRE 16 -1 (-500 5375)(-500 5325);
WIRE 16 -1 (-500 5325)(-800 5325);
WIRE 16 -1 (-500 5425)(-500 5375);
WIRE 16 -1 (-500 5375)(-800 5375);
WIRE 16 -1 (-500 5475)(-500 5425);
WIRE 16 -1 (-500 5425)(-800 5425);
WIRE 16 -1 (-500 5525)(-500 5475);
WIRE 16 -1 (-500 5475)(-800 5475);
WIRE 16 -1 (-500 5575)(-500 5525);
WIRE 16 -1 (-500 5525)(-800 5525);
WIRE 16 -1 (-500 5575)(-800 5575);
WIRE 16 -1 (-2400 5825)(-2400 5950);
WIRE 16 -1 (-2400 5825)(-2975 5825);
WIRE 16 -1 (-2975 5825)(-2975 5950);
WIRE 16 -1 (-2975 5825)(-2975 5750);
WIRE 16 -1 (-2400 6250)(-2300 6250);
WIRE 16 -1 (-2400 6250)(-2400 6150);
WIRE 16 -1 (-2400 6250)(-2975 6250);
WIRE 16 -1 (-2300 5575)(-2300 6250);
WIRE 16 -1 (-2000 5575)(-2300 5575);
WIRE 16 -1 (-2300 5525)(-2300 5575);
WIRE 16 -1 (-2975 6150)(-2975 6250);
WIRE 16 -1 (-2975 6250)(-2975 6325);
WIRE 16 -1 (-2000 5525)(-2300 5525);
WIRE 16 -1 (-2300 5525)(-2300 5475);
WIRE 16 -1 (-2300 5475)(-2000 5475);
WIRE 16 -1 (-6325 2825)(-6525 2825);
WIRE 16 -1 (-3875 3875)(-3725 3875);
WIRE 16 -1 (-2000 2375)(-2300 2375);
WIRE 16 -1 (-2300 2425)(-2300 2375);
WIRE 16 -1 (-2300 2375)(-2300 2325);
WIRE 16 -1 (-2000 2325)(-2300 2325);
WIRE 16 -1 (-2300 2325)(-2300 2225);
WIRE 16 -1 (-2000 2425)(-2300 2425);
WIRE 16 -1 (-2300 2475)(-2300 2425);
WIRE 16 -1 (-2000 2475)(-2300 2475);
WIRE 16 -1 (-2300 2525)(-2300 2475);
WIRE 16 -1 (-2000 2525)(-2300 2525);
WIRE 16 -1 (-2300 2575)(-2300 2525);
WIRE 16 -1 (-2000 2575)(-2300 2575);
WIRE 16 -1 (-2300 2625)(-2300 2575);
WIRE 16 -1 (-2000 2625)(-2300 2625);
WIRE 16 -1 (-2300 2675)(-2300 2625);
WIRE 16 -1 (-2000 2675)(-2300 2675);
WIRE 16 -1 (-2300 2725)(-2300 2675);
WIRE 16 -1 (-2000 2725)(-2300 2725);
WIRE 16 -1 (-2300 2775)(-2300 2725);
WIRE 16 -1 (-2000 2775)(-2300 2775);
WIRE 16 -1 (-2300 2825)(-2300 2775);
WIRE 16 -1 (-2000 2825)(-2300 2825);
WIRE 16 -1 (-2300 2875)(-2300 2825);
WIRE 16 -1 (-2000 2875)(-2300 2875);
WIRE 16 -1 (-2300 2925)(-2300 2875);
WIRE 16 -1 (-2000 2925)(-2300 2925);
WIRE 16 -1 (-2300 2975)(-2300 2925);
WIRE 16 -1 (-2000 2975)(-2300 2975);
WIRE 16 -1 (-2300 3025)(-2300 2975);
WIRE 16 -1 (-2000 3025)(-2300 3025);
WIRE 16 -1 (-2300 3075)(-2300 3025);
WIRE 16 -1 (-2000 3075)(-2300 3075);
WIRE 16 -1 (-2300 3125)(-2300 3075);
WIRE 16 -1 (-2000 3125)(-2300 3125);
WIRE 16 -1 (-2300 3175)(-2300 3125);
WIRE 16 -1 (-2000 3175)(-2300 3175);
WIRE 16 -1 (-2300 3225)(-2300 3175);
WIRE 16 -1 (-2000 3225)(-2300 3225);
WIRE 16 -1 (-2300 3275)(-2300 3225);
WIRE 16 -1 (-2000 3275)(-2300 3275);
WIRE 16 -1 (-2300 3325)(-2300 3275);
WIRE 16 -1 (-2000 3325)(-2300 3325);
WIRE 16 -1 (-2300 3375)(-2300 3325);
WIRE 16 -1 (-2000 3375)(-2300 3375);
WIRE 16 -1 (-2300 3425)(-2300 3375);
WIRE 16 -1 (-2000 3425)(-2300 3425);
WIRE 16 -1 (-2300 3475)(-2300 3425);
WIRE 16 -1 (-2000 3475)(-2300 3475);
WIRE 16 -1 (-2300 3525)(-2300 3475);
WIRE 16 -1 (-2000 3525)(-2300 3525);
WIRE 16 -1 (-2300 3575)(-2300 3525);
WIRE 16 -1 (-2000 3575)(-2300 3575);
WIRE 16 -1 (-2300 3625)(-2300 3575);
WIRE 16 -1 (-2000 3625)(-2300 3625);
WIRE 16 -1 (-2300 3675)(-2300 3625);
WIRE 16 -1 (-2000 3675)(-2300 3675);
WIRE 16 -1 (-2300 3725)(-2300 3675);
WIRE 16 -1 (-2000 3725)(-2300 3725);
WIRE 16 -1 (-2300 3775)(-2300 3725);
WIRE 16 -1 (-2000 3775)(-2300 3775);
WIRE 16 -1 (-2300 3825)(-2300 3775);
WIRE 16 -1 (-2000 3825)(-2300 3825);
WIRE 16 -1 (-2300 3875)(-2300 3825);
WIRE 16 -1 (-2000 3875)(-2300 3875);
WIRE 16 -1 (-2300 3925)(-2300 3875);
WIRE 16 -1 (-2000 3925)(-2300 3925);
WIRE 16 -1 (-2300 3975)(-2300 3925);
WIRE 16 -1 (-2000 3975)(-2300 3975);
WIRE 16 -1 (-2300 4025)(-2300 3975);
WIRE 16 -1 (-2000 4025)(-2300 4025);
WIRE 16 -1 (-2300 4075)(-2300 4025);
WIRE 16 -1 (-2300 4125)(-2300 4075);
WIRE 16 -1 (-2000 4075)(-2300 4075);
WIRE 16 -1 (-2000 4125)(-2300 4125);
WIRE 16 -1 (-2300 4175)(-2300 4125);
WIRE 16 -1 (-2000 4175)(-2300 4175);
WIRE 16 -1 (-2300 4225)(-2300 4175);
WIRE 16 -1 (-2000 4225)(-2300 4225);
WIRE 16 -1 (-2300 4275)(-2300 4225);
WIRE 16 -1 (-2000 4275)(-2300 4275);
WIRE 16 -1 (-2300 4325)(-2300 4275);
WIRE 16 -1 (-2000 4325)(-2300 4325);
WIRE 16 -1 (-2300 4375)(-2300 4325);
WIRE 16 -1 (-2000 4375)(-2300 4375);
WIRE 16 -1 (-2300 4425)(-2300 4375);
WIRE 16 -1 (-2000 4425)(-2300 4425);
WIRE 16 -1 (-2300 4475)(-2300 4425);
WIRE 16 -1 (-2000 4475)(-2300 4475);
WIRE 16 -1 (-2300 4525)(-2300 4475);
WIRE 16 -1 (-2000 4525)(-2300 4525);
WIRE 16 -1 (-2300 4575)(-2300 4525);
WIRE 16 -1 (-2000 4575)(-2300 4575);
WIRE 16 -1 (-2300 4625)(-2300 4575);
WIRE 16 -1 (-2000 4625)(-2300 4625);
WIRE 16 -1 (-2300 4675)(-2300 4625);
WIRE 16 -1 (-2000 4675)(-2300 4675);
WIRE 16 -1 (-2300 4725)(-2300 4675);
WIRE 16 -1 (-2000 4725)(-2300 4725);
WIRE 16 -1 (-2300 4775)(-2300 4725);
WIRE 16 -1 (-2000 4775)(-2300 4775);
WIRE 16 -1 (-2300 4825)(-2300 4775);
WIRE 16 -1 (-2000 4825)(-2300 4825);
WIRE 16 -1 (-2300 4875)(-2300 4825);
WIRE 16 -1 (-2000 4875)(-2300 4875);
WIRE 16 -1 (-2300 4925)(-2300 4875);
WIRE 16 -1 (-2000 4925)(-2300 4925);
WIRE 16 -1 (-2300 4975)(-2300 4925);
WIRE 16 -1 (-2000 4975)(-2300 4975);
WIRE 16 -1 (-2300 5025)(-2300 4975);
WIRE 16 -1 (-2000 5025)(-2300 5025);
WIRE 16 -1 (-2300 5075)(-2300 5025);
WIRE 16 -1 (-2000 5075)(-2300 5075);
WIRE 16 -1 (-2300 5125)(-2300 5075);
WIRE 16 -1 (-2000 5125)(-2300 5125);
WIRE 16 -1 (-2300 5175)(-2300 5125);
WIRE 16 -1 (-2000 5175)(-2300 5175);
WIRE 16 -1 (-2300 5225)(-2300 5175);
WIRE 16 -1 (-2000 5225)(-2300 5225);
WIRE 16 -1 (-2300 5275)(-2300 5225);
WIRE 16 -1 (-2000 5275)(-2300 5275);
WIRE 16 -1 (-2300 5325)(-2300 5275);
WIRE 16 -1 (-2000 5325)(-2300 5325);
WIRE 16 -1 (-2300 5375)(-2300 5325);
WIRE 16 -1 (-2000 5375)(-2300 5375);
WIRE 16 -1 (-2300 5425)(-2300 5375);
WIRE 16 -1 (-2000 5425)(-2300 5425);
WIRE 16 -1 (-3875 3475)(-3525 3475);
WIRE 16 -1 (-3875 3375)(-3525 3375);
WIRE 16 -1 (-3875 3575)(-3525 3575);
WIRE 16 -1 (-3875 3625)(-3725 3625);
WIRE 16 -1 (-3875 3725)(-3525 3725);
WIRE 16 -1 (-6325 4675)(-6525 4675);
WIRE 16 -1 (-6325 4875)(-6525 4875);
WIRE 16 -1 (-3875 4675)(-3725 4675);
WIRE 16 -1 (-3725 4575)(-3875 4575);
WIRE 16 -1 (-3875 4525)(-3525 4525);
WIRE 16 -1 (-3875 4625)(-3525 4625);
WIRE 16 -1 (-3875 4425)(-3525 4425);
WIRE 16 -1 (-6325 3225)(-6525 3225);
WIRE 16 -1 (-7725 3275)(-8375 3275);
FORCEPROP 2 LAST SIG_NAME M_E_CPU0_RESET_N
J 0
(-8360 3285);
DISPLAY 0.489362 (-8360 3285);
DOT 1 (-8775 3525);
DOT 1 (-2300 5275);
DOT 1 (-2300 5025);
DOT 1 (-2300 4075);
DOT 1 (-2300 4525);
DOT 1 (-500 5475);
DOT 1 (-500 5525);
DOT 1 (-500 5425);
DOT 1 (-500 5325);
DOT 1 (-500 5375);
DOT 1 (-500 5225);
DOT 1 (-500 5275);
DOT 1 (-500 5175);
DOT 1 (-500 5075);
DOT 1 (-500 5125);
DOT 1 (-500 5025);
DOT 1 (-500 4975);
DOT 1 (-500 4925);
DOT 1 (-500 4825);
DOT 1 (-500 4875);
DOT 1 (-500 4775);
DOT 1 (-500 4725);
DOT 1 (-500 4675);
DOT 1 (-500 4575);
DOT 1 (-500 4625);
DOT 1 (-500 4475);
DOT 1 (-500 4525);
DOT 1 (-500 4425);
DOT 1 (-500 4375);
DOT 1 (-500 4325);
DOT 1 (-2300 5325);
DOT 1 (-2300 5375);
DOT 1 (-2300 5225);
DOT 1 (-2300 5175);
DOT 1 (-2300 5125);
DOT 1 (-2300 5075);
DOT 1 (-2300 4975);
DOT 1 (-2300 4925);
DOT 1 (-2300 4825);
DOT 1 (-2300 4875);
DOT 1 (-2300 4675);
DOT 1 (-2300 4725);
DOT 1 (-2300 4775);
DOT 1 (-2300 4625);
DOT 1 (-2300 4575);
DOT 1 (-2300 4425);
DOT 1 (-2300 4475);
DOT 1 (-2300 4325);
DOT 1 (-2300 4375);
DOT 1 (-2300 4275);
DOT 1 (-500 4275);
DOT 1 (-500 4175);
DOT 1 (-500 4225);
DOT 1 (-500 4125);
DOT 1 (-500 4075);
DOT 1 (-500 4025);
DOT 1 (-500 3925);
DOT 1 (-500 3975);
DOT 1 (-500 3875);
DOT 1 (-500 3825);
DOT 1 (-500 3775);
DOT 1 (-500 3725);
DOT 1 (-500 3675);
DOT 1 (-500 3625);
DOT 1 (-500 3575);
DOT 1 (-500 3525);
DOT 1 (-500 3425);
DOT 1 (-500 3475);
DOT 1 (-500 3375);
DOT 1 (-500 3325);
DOT 1 (-500 3275);
DOT 1 (-500 3175);
DOT 1 (-500 3225);
DOT 1 (-500 3125);
DOT 1 (-500 3025);
DOT 1 (-500 3075);
DOT 1 (-500 2975);
DOT 1 (-500 2925);
DOT 1 (-500 2875);
DOT 1 (-500 2775);
DOT 1 (-500 2825);
DOT 1 (-500 2675);
DOT 1 (-500 2725);
DOT 1 (-500 2625);
DOT 1 (-500 2525);
DOT 1 (-500 2575);
DOT 1 (-500 2475);
DOT 1 (-500 2425);
DOT 1 (-500 2325);
DOT 1 (-500 2275);
DOT 1 (-500 2225);
DOT 1 (-2300 4225);
DOT 1 (-2300 4175);
DOT 1 (-2300 4125);
DOT 1 (-2300 4025);
DOT 1 (-2300 3925);
DOT 1 (-2300 3975);
DOT 1 (-2300 3775);
DOT 1 (-2300 3825);
DOT 1 (-2300 3875);
DOT 1 (-2300 3725);
DOT 1 (-2300 3675);
DOT 1 (-2300 3625);
DOT 1 (-2300 3525);
DOT 1 (-2300 3575);
DOT 1 (-2300 3425);
DOT 1 (-2300 3475);
DOT 1 (-2300 3375);
DOT 1 (-2300 3325);
DOT 1 (-2300 3275);
DOT 1 (-2300 3175);
DOT 1 (-2300 3225);
DOT 1 (-2300 3125);
DOT 1 (-2300 3075);
DOT 1 (-2300 3025);
DOT 1 (-2300 2925);
DOT 1 (-2300 2975);
DOT 1 (-2300 2875);
DOT 1 (-2300 2775);
DOT 1 (-2300 2825);
DOT 1 (-2300 2725);
DOT 1 (-2300 2625);
DOT 1 (-2300 2675);
DOT 1 (-2300 2575);
DOT 1 (-2300 2525);
DOT 1 (-2300 2375);
DOT 1 (-2300 2425);
DOT 1 (-2300 2475);
DOT 1 (-2300 2325);
DOT 1 (-2300 5575);
DOT 1 (-2300 5525);
DOT 1 (-8600 2325);
DOT 1 (-2975 5825);
DOT 1 (-2400 6250);
DOT 1 (-2975 6250);
QUIT
